FILE_TYPE = MACRO_DRAWING;
SET COLOR_WIRE YELLOW;
SET COLOR_PROP MONO;
SET COLOR_DOT WHITE;
SET COLOR_ARC YELLOW;
SET COLOR_BODY GREEN;
SET COLOR_NOTE MONO;
SET PROP_DISPLAY VALUE;
SET PAGE_NUMBER P176;
FORCEADD TPS2061..1
(-4125 3325);
FORCEPROP 1 LAST LOCATION U1M3
J 0
(-4375 3675);
DISPLAY 0.617021 (-4375 3675);
PAINT AQUA (-4375 3675);
FORCEPROP 2 LASTPIN (-4425 3425) $PN 5
J 2
(-4435 3435);
DISPLAY 0.617021 (-4435 3435);
PAINT ORANGE (-4435 3435);
FORCEPROP 2 LASTPIN (-3825 3125) $PN 2
J 0
(-3815 3135);
DISPLAY 0.617021 (-3815 3135);
PAINT ORANGE (-3815 3135);
FORCEPROP 2 LASTPIN (-3825 3425) $PN 1
J 0
(-3815 3435);
DISPLAY 0.617021 (-3815 3435);
PAINT ORANGE (-3815 3435);
FORCEPROP 1 LAST MATERIAL IC
J 0
(-4375 3625);
DISPLAY 0.617021 (-4375 3625);
PAINT SKYBLUE (-4375 3625);
FORCEPROP 2 LASTPIN (-3825 3325) $PN 3
J 0
(-3815 3335);
DISPLAY 0.617021 (-3815 3335);
PAINT ORANGE (-3815 3335);
FORCEPROP 2 LASTPIN (-4425 3225) $PN 4
J 2
(-4435 3235);
DISPLAY 0.617021 (-4435 3235);
PAINT ORANGE (-4435 3235);
FORCEPROP 1 LAST PART_NUMBER H66405-001
J 0
(-4375 3025);
DISPLAY 0.617021 (-4375 3025);
PAINT BLUE (-4375 3025);
FORCEPROP 0 LAST ROOM USB_REAR
J 0
(-4375 3775);
DISPLAY 1.021277 (-4375 3775);
PAINT ORANGE (-4375 3775);
DISPLAY INVISIBLE (-4375 3775);
FORCEPROP 1 LAST PATH I100
J 0
(-4075 3625);
PAINT GREEN (-4075 3625);
DISPLAY INVISIBLE (-4075 3625);
FORCEPROP 2 LAST SEC 1
J 0
(-4375 3725);
DISPLAY 0.680851 (-4375 3725);
PAINT MONO (-4375 3725);
DISPLAY INVISIBLE (-4375 3725);
FORCEPROP 0 LAST BOM_COST MIO_USB
J 0
(-4375 3775);
DISPLAY 1.021277 (-4375 3775);
PAINT ORANGE (-4375 3775);
DISPLAY INVISIBLE (-4375 3775);
FORCEPROP 2 LAST SEC_TYPE SM
J 0
(-4375 3725);
DISPLAY 1.021277 (-4375 3725);
PAINT ORANGE (-4375 3725);
DISPLAY INVISIBLE (-4375 3725);
FORCEPROP 1 LAST PACK_TYPE SM
J 0
(-4375 3725);
PAINT SKYBLUE (-4375 3725);
DISPLAY INVISIBLE (-4375 3725);
FORCEPROP 2 LAST CDS_LIB mstr_vreg
J 0
(-4125 3325);
PAINT MONO (-4125 3325);
DISPLAY INVISIBLE (-4125 3325);
FORCEADD P5V..1
(-4950 4150);
FORCEPROP 3 LASTPIN (-4950 4100) SIG_NAME P5V\g
J 0
(-4940 4110);
DISPLAY 0.659574 (-4940 4110);
PAINT MONO (-4940 4110);
DISPLAY INVISIBLE (-4940 4110);
FORCEPROP 1 LAST HDL_POWER P5V
J 0
(-5250 4025);
DISPLAY 0.872340 (-5250 4025);
PAINT ORANGE (-5250 4025);
DISPLAY INVISIBLE (-5250 4025);
FORCEPROP 1 LAST BODY_TYPE PLUMBING
J 0
(-4995 4107);
DISPLAY 0.340426 (-4995 4107);
PAINT GREEN (-4995 4107);
DISPLAY INVISIBLE (-4995 4107);
FORCEPROP 1 LAST VOLTAGE 5.0V
J 0
(-4995 4107);
DISPLAY 0.340426 (-4995 4107);
PAINT SKYBLUE (-4995 4107);
DISPLAY INVISIBLE (-4995 4107);
FORCEPROP 1 LAST SIZE 1B
J 0
(-4905 4172);
DISPLAY 0.340426 (-4905 4172);
PAINT GREEN (-4905 4172);
DISPLAY INVISIBLE (-4905 4172);
FORCEPROP 2 LAST CDS_LIB mstr_symbols
J 0
(-4950 4150);
PAINT MONO (-4950 4150);
DISPLAY INVISIBLE (-4950 4150);
FORCEPROP 1 LAST PATH I101
J 0
(-4905 4152);
DISPLAY 0.340426 (-4905 4152);
PAINT GREEN (-4905 4152);
DISPLAY INVISIBLE (-4905 4152);
FORCEADD GND..1
(-3750 2950);
FORCEPROP 3 LASTPIN (-3750 3000) SIG_NAME GND\g
J 0
(-3740 3010);
DISPLAY 0.659574 (-3740 3010);
PAINT MONO (-3740 3010);
DISPLAY INVISIBLE (-3740 3010);
FORCEPROP 1 LAST HDL_POWER GND
J 0
(-3750 3100);
DISPLAY 0.872340 (-3750 3100);
PAINT GREEN (-3750 3100);
DISPLAY INVISIBLE (-3750 3100);
FORCEPROP 1 LAST BODY_TYPE PLUMBING
J 0
(-3795 2907);
DISPLAY 0.340426 (-3795 2907);
PAINT GREEN (-3795 2907);
DISPLAY INVISIBLE (-3795 2907);
FORCEPROP 1 LAST PATH I102
J 0
(-3675 2950);
DISPLAY 0.872340 (-3675 2950);
PAINT AQUA (-3675 2950);
DISPLAY INVISIBLE (-3675 2950);
FORCEPROP 1 LAST SIZE 1B
J 0
(-3675 2900);
DISPLAY 0.872340 (-3675 2900);
PAINT AQUA (-3675 2900);
DISPLAY INVISIBLE (-3675 2900);
FORCEPROP 1 LAST VOLTAGE 0
J 0
(-3750 2950);
PAINT SKYBLUE (-3750 2950);
DISPLAY INVISIBLE (-3750 2950);
FORCEPROP 2 LAST CDS_LIB mstr_symbols
J 0
(-3750 2950);
PAINT ORANGE (-3750 2950);
DISPLAY INVISIBLE (-3750 2950);
FORCEADD OFFPAGE..2
(-3200 3425);
FORCEPROP 2 LAST $XR0 176 
J 0
(-3011 3425);
DISPLAY 0.638298 (-3011 3425);
PAINT MONO (-3011 3425);
FORCEPROP 2 LAST PATH I103
J 0
(-3000 3475);
DISPLAY 1.021277 (-3000 3475);
PAINT ORANGE (-3000 3475);
DISPLAY INVISIBLE (-3000 3475);
FORCEPROP 2 LAST CDS_LIB mstr_standard
J 0
(-3200 3425);
PAINT ORANGE (-3200 3425);
DISPLAY INVISIBLE (-3200 3425);
FORCEPROP 1 LAST OFFPAGE TRUE
J 0
(-2875 3300);
DISPLAY 0.872340 (-2875 3300);
PAINT GREEN (-2875 3300);
DISPLAY INVISIBLE (-2875 3300);
FORCEPROP 1 LAST COMMENT_BODY TRUE
J 0
(-3245 3330);
DISPLAY 0.872340 (-3245 3330);
PAINT GREEN (-3245 3330);
DISPLAY INVISIBLE (-3245 3330);
FORCEADD OFFPAGE..2
(-3200 3325);
FORCEPROP 2 LAST $XR1 190 
J 0
(-2891 3325);
DISPLAY 0.638298 (-2891 3325);
PAINT MONO (-2891 3325);
FORCEPROP 2 LAST $XR0 120 
J 0
(-3011 3325);
DISPLAY 0.638298 (-3011 3325);
PAINT MONO (-3011 3325);
FORCEPROP 2 LAST CDS_LIB mstr_standard
J 0
(-3200 3325);
PAINT ORANGE (-3200 3325);
DISPLAY INVISIBLE (-3200 3325);
FORCEPROP 2 LAST PATH I104
J 0
(-3000 3375);
DISPLAY 1.021277 (-3000 3375);
PAINT ORANGE (-3000 3375);
DISPLAY INVISIBLE (-3000 3375);
FORCEPROP 1 LAST OFFPAGE TRUE
J 0
(-2875 3200);
DISPLAY 0.872340 (-2875 3200);
PAINT GREEN (-2875 3200);
DISPLAY INVISIBLE (-2875 3200);
FORCEPROP 1 LAST COMMENT_BODY TRUE
J 0
(-3245 3230);
DISPLAY 0.872340 (-3245 3230);
PAINT GREEN (-3245 3230);
DISPLAY INVISIBLE (-3245 3230);
FORCEADD RES..2
(-3700 3675);
FORCEPROP 1 LAST LOCATION R1M24
J 0
(-3655 3800);
DISPLAY 0.617021 (-3655 3800);
PAINT AQUA (-3655 3800);
FORCEPROP 1 LAST PART_NUMBER G21796-016
J 0
(-3660 3550);
DISPLAY 0.617021 (-3660 3550);
PAINT BLUE (-3660 3550);
FORCEPROP 1 LAST WATTAGE 1/16W
J 0
(-3660 3650);
DISPLAY 0.617021 (-3660 3650);
PAINT SKYBLUE (-3660 3650);
FORCEPROP 1 LASTPIN (-3700 3775) $PN 1
J 0
(-3695 3737);
DISPLAY 0.617021 (-3695 3737);
PAINT ORANGE (-3695 3737);
FORCEPROP 1 LAST MATERIAL CHIP
J 0
(-3660 3600);
DISPLAY 0.617021 (-3660 3600);
PAINT SKYBLUE (-3660 3600);
FORCEPROP 1 LASTPIN (-3700 3575) $PN 2
J 0
(-3695 3585);
DISPLAY 0.617021 (-3695 3585);
PAINT ORANGE (-3695 3585);
FORCEPROP 1 LAST PACK_TYPE 0402
J 0
(-3660 3500);
DISPLAY 0.617021 (-3660 3500);
PAINT SKYBLUE (-3660 3500);
FORCEPROP 1 LAST TOLERANCE 1%
J 0
(-3655 3700);
DISPLAY 0.617021 (-3655 3700);
PAINT SKYBLUE (-3655 3700);
FORCEPROP 1 LAST VALUE 10.0K
J 0
(-3655 3750);
DISPLAY 0.617021 (-3655 3750);
PAINT SKYBLUE (-3655 3750);
FORCEPROP 1 LAST PATH I105
J 0
(-3650 3850);
DISPLAY 0.978723 (-3650 3850);
PAINT WHITE (-3650 3850);
DISPLAY INVISIBLE (-3650 3850);
FORCEPROP 2 LAST CDS_LIB mstr_discrete
J 0
(-3700 3675);
PAINT MONO (-3700 3675);
DISPLAY INVISIBLE (-3700 3675);
FORCEPROP 2 LAST ROOM USB_REAR
J 0
(-3700 3675);
PAINT MONO (-3700 3675);
DISPLAY INVISIBLE (-3700 3675);
FORCEPROP 2 LAST SEC 1
J 0
(-3650 3900);
DISPLAY 0.680851 (-3650 3900);
PAINT MONO (-3650 3900);
DISPLAY INVISIBLE (-3650 3900);
FORCEPROP 2 LAST SEC_TYPE 0402
J 0
(-3650 3900);
DISPLAY 1.021277 (-3650 3900);
PAINT ORANGE (-3650 3900);
DISPLAY INVISIBLE (-3650 3900);
FORCEPROP 0 LAST BOM_COST MIO_USB
J 0
(-3650 3900);
DISPLAY 1.021277 (-3650 3900);
PAINT ORANGE (-3650 3900);
DISPLAY INVISIBLE (-3650 3900);
FORCEADD CAP_A..1
(-5225 3525);
FORCEPROP 1 LAST PACK_TYPE 0402V
J 0
(-5175 3325);
DISPLAY 0.617021 (-5175 3325);
PAINT SKYBLUE (-5175 3325);
FORCEPROP 1 LAST LOCATION C1M38
J 0
(-5175 3625);
DISPLAY 0.617021 (-5175 3625);
PAINT AQUA (-5175 3625);
FORCEPROP 1 LAST TOLERANCE 10%
J 0
(-5175 3475);
DISPLAY 0.617021 (-5175 3475);
PAINT SKYBLUE (-5175 3475);
FORCEPROP 1 LAST VOLTAGE 16V
J 0
(-5175 3525);
DISPLAY 0.617021 (-5175 3525);
PAINT SKYBLUE (-5175 3525);
FORCEPROP 1 LAST VALUE 0.1UF
J 0
(-5175 3575);
DISPLAY 0.617021 (-5175 3575);
PAINT SKYBLUE (-5175 3575);
FORCEPROP 1 LASTPIN (-5225 3625) $PN 1
J 0
(-5215 3605);
DISPLAY 0.617021 (-5215 3605);
PAINT ORANGE (-5215 3605);
FORCEPROP 1 LASTPIN (-5225 3425) $PN 2
J 0
(-5215 3405);
DISPLAY 0.617021 (-5215 3405);
PAINT ORANGE (-5215 3405);
FORCEPROP 1 LAST PART_NUMBER A36096-030
J 0
(-5175 3375);
DISPLAY 0.617021 (-5175 3375);
PAINT BLUE (-5175 3375);
FORCEPROP 1 LAST MATERIAL X7R
J 0
(-5175 3425);
DISPLAY 0.617021 (-5175 3425);
PAINT SKYBLUE (-5175 3425);
FORCEPROP 0 LAST BOM_COST MIO_USB
J 0
(-5175 3725);
DISPLAY 1.021277 (-5175 3725);
PAINT ORANGE (-5175 3725);
DISPLAY INVISIBLE (-5175 3725);
FORCEPROP 2 LAST SEC_TYPE 0402V
J 0
(-5175 3725);
DISPLAY 1.021277 (-5175 3725);
PAINT ORANGE (-5175 3725);
DISPLAY INVISIBLE (-5175 3725);
FORCEPROP 2 LAST SEC 1
J 0
(-5175 3725);
PAINT MONO (-5175 3725);
DISPLAY INVISIBLE (-5175 3725);
FORCEPROP 2 LAST CDS_SEC 1
J 0
(-5175 3675);
PAINT ORANGE (-5175 3675);
DISPLAY INVISIBLE (-5175 3675);
FORCEPROP 0 LAST ROOM USB_REAR
J 0
(-5175 3675);
DISPLAY 1.021277 (-5175 3675);
PAINT ORANGE (-5175 3675);
DISPLAY INVISIBLE (-5175 3675);
FORCEPROP 1 LAST PATH I108
J 0
(-5175 3675);
DISPLAY 0.978723 (-5175 3675);
PAINT WHITE (-5175 3675);
DISPLAY INVISIBLE (-5175 3675);
FORCEPROP 2 LAST CDS_LIB dev_discrete
J 0
(-5225 3525);
PAINT ORANGE (-5225 3525);
DISPLAY INVISIBLE (-5225 3525);
FORCEADD GND..1
(-5225 3325);
FORCEPROP 3 LASTPIN (-5225 3375) SIG_NAME GND\g
J 0
(-5215 3385);
DISPLAY 0.659574 (-5215 3385);
PAINT MONO (-5215 3385);
DISPLAY INVISIBLE (-5215 3385);
FORCEPROP 1 LAST HDL_POWER GND
J 0
(-5225 3475);
DISPLAY 0.872340 (-5225 3475);
PAINT GREEN (-5225 3475);
DISPLAY INVISIBLE (-5225 3475);
FORCEPROP 1 LAST BODY_TYPE PLUMBING
J 0
(-5270 3282);
DISPLAY 0.340426 (-5270 3282);
PAINT GREEN (-5270 3282);
DISPLAY INVISIBLE (-5270 3282);
FORCEPROP 1 LAST PATH I109
J 0
(-5150 3325);
DISPLAY 0.872340 (-5150 3325);
PAINT AQUA (-5150 3325);
DISPLAY INVISIBLE (-5150 3325);
FORCEPROP 1 LAST SIZE 1B
J 0
(-5150 3275);
DISPLAY 0.872340 (-5150 3275);
PAINT AQUA (-5150 3275);
DISPLAY INVISIBLE (-5150 3275);
FORCEPROP 1 LAST VOLTAGE 0
J 0
(-5225 3325);
PAINT SKYBLUE (-5225 3325);
DISPLAY INVISIBLE (-5225 3325);
FORCEPROP 2 LAST CDS_LIB mstr_symbols
J 0
(-5225 3325);
PAINT MONO (-5225 3325);
DISPLAY INVISIBLE (-5225 3325);
FORCEADD P3V3_STBY..1
(-3700 3875);
FORCEPROP 3 LASTPIN (-3700 3825) SIG_NAME P3V3_STBY\g
J 0
(-3690 3835);
DISPLAY 0.659574 (-3690 3835);
PAINT MONO (-3690 3835);
DISPLAY INVISIBLE (-3690 3835);
FORCEPROP 2 LAST CDS_LIB mstr_symbols
J 0
(-3700 3875);
PAINT MONO (-3700 3875);
DISPLAY INVISIBLE (-3700 3875);
FORCEPROP 1 LAST SIZE 1B
J 0
(-3655 3897);
DISPLAY 0.340426 (-3655 3897);
PAINT GREEN (-3655 3897);
DISPLAY INVISIBLE (-3655 3897);
FORCEPROP 1 LAST VOLTAGE 3.3V
J 0
(-3745 3832);
DISPLAY 0.340426 (-3745 3832);
PAINT SKYBLUE (-3745 3832);
DISPLAY INVISIBLE (-3745 3832);
FORCEPROP 1 LAST BODY_TYPE PLUMBING
J 0
(-3745 3832);
DISPLAY 0.340426 (-3745 3832);
PAINT GREEN (-3745 3832);
DISPLAY INVISIBLE (-3745 3832);
FORCEPROP 1 LAST HDL_POWER P3V3_STBY
J 0
(-4000 3750);
DISPLAY 0.872340 (-4000 3750);
PAINT ORANGE (-4000 3750);
DISPLAY INVISIBLE (-4000 3750);
FORCEPROP 1 LAST PATH I110
J 0
(-3655 3877);
DISPLAY 0.340426 (-3655 3877);
PAINT GREEN (-3655 3877);
DISPLAY INVISIBLE (-3655 3877);
FORCEADD RES..2
(-5200 3000);
FORCEPROP 1 LASTPIN (-5200 3100) $PN 1
J 0
(-5195 3062);
DISPLAY 0.617021 (-5195 3062);
PAINT ORANGE (-5195 3062);
FORCEPROP 1 LAST VALUE 10.0K
J 0
(-5155 3075);
DISPLAY 0.617021 (-5155 3075);
PAINT SKYBLUE (-5155 3075);
FORCEPROP 1 LAST LOCATION R1M25
J 0
(-5155 3125);
DISPLAY 0.617021 (-5155 3125);
PAINT AQUA (-5155 3125);
FORCEPROP 1 LAST PACK_TYPE 0402
J 0
(-5160 2825);
DISPLAY 0.617021 (-5160 2825);
PAINT SKYBLUE (-5160 2825);
FORCEPROP 1 LAST WATTAGE 1/16W
J 0
(-5160 2975);
DISPLAY 0.617021 (-5160 2975);
PAINT SKYBLUE (-5160 2975);
FORCEPROP 1 LAST MATERIAL CHIP
J 0
(-5160 2925);
DISPLAY 0.617021 (-5160 2925);
PAINT SKYBLUE (-5160 2925);
FORCEPROP 1 LAST PART_NUMBER G21796-016
J 0
(-5160 2875);
DISPLAY 0.617021 (-5160 2875);
PAINT BLUE (-5160 2875);
FORCEPROP 1 LASTPIN (-5200 2900) $PN 2
J 0
(-5195 2910);
DISPLAY 0.617021 (-5195 2910);
PAINT ORANGE (-5195 2910);
FORCEPROP 1 LAST TOLERANCE 1%
J 0
(-5155 3025);
DISPLAY 0.617021 (-5155 3025);
PAINT SKYBLUE (-5155 3025);
FORCEPROP 0 LAST BOM_COST MIO_USB
J 0
(-5150 3225);
DISPLAY 1.021277 (-5150 3225);
PAINT ORANGE (-5150 3225);
DISPLAY INVISIBLE (-5150 3225);
FORCEPROP 2 LAST SEC_TYPE 0402
J 0
(-5150 3225);
DISPLAY 1.021277 (-5150 3225);
PAINT ORANGE (-5150 3225);
DISPLAY INVISIBLE (-5150 3225);
FORCEPROP 1 LAST PATH I111
J 0
(-5150 3175);
DISPLAY 0.978723 (-5150 3175);
PAINT WHITE (-5150 3175);
DISPLAY INVISIBLE (-5150 3175);
FORCEPROP 2 LAST SEC 1
J 0
(-5150 3225);
DISPLAY 0.680851 (-5150 3225);
PAINT MONO (-5150 3225);
DISPLAY INVISIBLE (-5150 3225);
FORCEPROP 2 LAST CDS_LIB mstr_discrete
J 0
(-5200 3000);
PAINT ORANGE (-5200 3000);
DISPLAY INVISIBLE (-5200 3000);
FORCEPROP 2 LAST ROOM USB_REAR
J 0
(-5200 3000);
PAINT MONO (-5200 3000);
DISPLAY INVISIBLE (-5200 3000);
FORCEADD GND..1
(-5200 2775);
FORCEPROP 3 LASTPIN (-5200 2825) SIG_NAME GND\g
J 0
(-5190 2835);
DISPLAY 0.659574 (-5190 2835);
PAINT MONO (-5190 2835);
DISPLAY INVISIBLE (-5190 2835);
FORCEPROP 1 LAST HDL_POWER GND
J 0
(-5200 2925);
DISPLAY 0.872340 (-5200 2925);
PAINT GREEN (-5200 2925);
DISPLAY INVISIBLE (-5200 2925);
FORCEPROP 1 LAST BODY_TYPE PLUMBING
J 0
(-5245 2732);
DISPLAY 0.340426 (-5245 2732);
PAINT GREEN (-5245 2732);
DISPLAY INVISIBLE (-5245 2732);
FORCEPROP 1 LAST PATH I112
J 0
(-5125 2775);
DISPLAY 0.872340 (-5125 2775);
PAINT AQUA (-5125 2775);
DISPLAY INVISIBLE (-5125 2775);
FORCEPROP 1 LAST SIZE 1B
J 0
(-5125 2725);
DISPLAY 0.872340 (-5125 2725);
PAINT AQUA (-5125 2725);
DISPLAY INVISIBLE (-5125 2725);
FORCEPROP 2 LAST CDS_LIB mstr_symbols
J 0
(-5200 2775);
PAINT ORANGE (-5200 2775);
DISPLAY INVISIBLE (-5200 2775);
FORCEPROP 1 LAST VOLTAGE 0
J 0
(-5200 2775);
PAINT SKYBLUE (-5200 2775);
DISPLAY INVISIBLE (-5200 2775);
FORCEADD CAPP..1
(-3650 3150);
FORCEPROP 1 LAST PART_NUMBER 724613-043
J 0
(-3600 2950);
DISPLAY 0.617021 (-3600 2950);
PAINT BLUE (-3600 2950);
FORCEPROP 1 LAST MATERIAL POSCAP
J 0
(-3600 3050);
DISPLAY 0.617021 (-3600 3050);
PAINT SKYBLUE (-3600 3050);
FORCEPROP 1 LAST PACK_TYPE 7343HLF
J 0
(-3600 3000);
DISPLAY 0.617021 (-3600 3000);
PAINT SKYBLUE (-3600 3000);
FORCEPROP 1 LAST VALUE 330UF
J 0
(-3600 3200);
DISPLAY 0.617021 (-3600 3200);
PAINT SKYBLUE (-3600 3200);
FORCEPROP 1 LAST TOLERANCE 20%
J 0
(-3600 3150);
DISPLAY 0.617021 (-3600 3150);
PAINT SKYBLUE (-3600 3150);
FORCEPROP 1 LASTPIN (-3650 3050) $PN 2
J 0
(-3640 3035);
DISPLAY 0.617021 (-3640 3035);
PAINT ORANGE (-3640 3035);
FORCEPROP 1 LAST LOCATION C9B8
J 0
(-3600 3250);
DISPLAY 0.617021 (-3600 3250);
PAINT AQUA (-3600 3250);
FORCEPROP 1 LASTPIN (-3650 3250) $PN 1
J 0
(-3640 3235);
DISPLAY 0.617021 (-3640 3235);
PAINT ORANGE (-3640 3235);
FORCEPROP 1 LAST VOLTAGE 10V
J 0
(-3600 3100);
DISPLAY 0.617021 (-3600 3100);
PAINT SKYBLUE (-3600 3100);
FORCEPROP 2 LAST CDS_LIB mstr_discrete
J 0
(-3650 3150);
PAINT ORANGE (-3650 3150);
DISPLAY INVISIBLE (-3650 3150);
FORCEPROP 2 LAST SEC_TYPE 7343HLF
J 0
(-3600 3350);
DISPLAY 1.021277 (-3600 3350);
PAINT ORANGE (-3600 3350);
DISPLAY INVISIBLE (-3600 3350);
FORCEPROP 2 LAST SEC 1
J 0
(-3600 3350);
DISPLAY 0.680851 (-3600 3350);
PAINT MONO (-3600 3350);
DISPLAY INVISIBLE (-3600 3350);
FORCEPROP 1 LAST PATH I113
J 0
(-3600 3300);
DISPLAY 0.978723 (-3600 3300);
PAINT ORANGE (-3600 3300);
DISPLAY INVISIBLE (-3600 3300);
FORCEADD GND..1
(-3650 2950);
FORCEPROP 3 LASTPIN (-3650 3000) SIG_NAME GND\g
J 0
(-3640 3010);
DISPLAY 0.659574 (-3640 3010);
PAINT MONO (-3640 3010);
DISPLAY INVISIBLE (-3640 3010);
FORCEPROP 1 LAST SIZE 1B
J 0
(-3575 2900);
DISPLAY 0.872340 (-3575 2900);
PAINT AQUA (-3575 2900);
DISPLAY INVISIBLE (-3575 2900);
FORCEPROP 1 LAST VOLTAGE 0
J 0
(-3650 2950);
PAINT SKYBLUE (-3650 2950);
DISPLAY INVISIBLE (-3650 2950);
FORCEPROP 2 LAST CDS_LIB mstr_symbols
J 0
(-3650 2950);
PAINT ORANGE (-3650 2950);
DISPLAY INVISIBLE (-3650 2950);
FORCEPROP 1 LAST PATH I114
J 0
(-3575 2950);
DISPLAY 0.872340 (-3575 2950);
PAINT AQUA (-3575 2950);
DISPLAY INVISIBLE (-3575 2950);
FORCEPROP 1 LAST BODY_TYPE PLUMBING
J 0
(-3695 2907);
DISPLAY 0.340426 (-3695 2907);
PAINT GREEN (-3695 2907);
DISPLAY INVISIBLE (-3695 2907);
FORCEPROP 1 LAST HDL_POWER GND
J 0
(-3650 3100);
DISPLAY 0.872340 (-3650 3100);
PAINT GREEN (-3650 3100);
DISPLAY INVISIBLE (-3650 3100);
FORCEADD OFFPAGE..2
(150 4400);
FORCEPROP 2 LAST $XR1 176 
J 0
(339 4364);
DISPLAY 0.638298 (339 4364);
PAINT MONO (339 4364);
FORCEPROP 2 LAST $XR0 168 
J 0
(339 4400);
DISPLAY 0.638298 (339 4400);
PAINT MONO (339 4400);
FORCEPROP 2 LAST PATH I119
J 0
(325 4475);
DISPLAY 1.021277 (325 4475);
PAINT ORANGE (325 4475);
DISPLAY INVISIBLE (325 4475);
FORCEPROP 2 LAST CDS_LIB mstr_standard
J 0
(150 4400);
PAINT MONO (150 4400);
DISPLAY INVISIBLE (150 4400);
FORCEPROP 1 LAST OFFPAGE TRUE
J 0
(475 4275);
DISPLAY 0.872340 (475 4275);
PAINT GREEN (475 4275);
DISPLAY INVISIBLE (475 4275);
FORCEPROP 1 LAST COMMENT_BODY TRUE
J 0
(105 4305);
DISPLAY 0.872340 (105 4305);
PAINT GREEN (105 4305);
DISPLAY INVISIBLE (105 4305);
FORCEADD OFFPAGE..2
(250 1850);
FORCEPROP 2 LAST $XR1 158 
J 0
(529 1814);
DISPLAY 0.638298 (529 1814);
PAINT MONO (529 1814);
FORCEPROP 2 LAST $XR0 181 
J 0
(529 1850);
DISPLAY 0.638298 (529 1850);
PAINT MONO (529 1850);
FORCEPROP 2 LAST PATH I123
J 0
(450 1900);
DISPLAY 1.021277 (450 1900);
PAINT ORANGE (450 1900);
DISPLAY INVISIBLE (450 1900);
FORCEPROP 2 LAST CDS_LIB mstr_standard
J 0
(250 1850);
PAINT MONO (250 1850);
DISPLAY INVISIBLE (250 1850);
FORCEPROP 1 LAST OFFPAGE TRUE
J 0
(575 1725);
DISPLAY 0.872340 (575 1725);
PAINT GREEN (575 1725);
DISPLAY INVISIBLE (575 1725);
FORCEPROP 1 LAST COMMENT_BODY TRUE
J 0
(205 1755);
DISPLAY 0.872340 (205 1755);
PAINT GREEN (205 1755);
DISPLAY INVISIBLE (205 1755);
FORCEADD GND..1
(-200 1325);
FORCEPROP 3 LASTPIN (-200 1375) SIG_NAME GND\g
J 0
(-190 1385);
DISPLAY 0.659574 (-190 1385);
PAINT MONO (-190 1385);
DISPLAY INVISIBLE (-190 1385);
FORCEPROP 1 LAST HDL_POWER GND
J 0
(-200 1475);
DISPLAY 1.170213 (-200 1475);
PAINT GREEN (-200 1475);
DISPLAY INVISIBLE (-200 1475);
FORCEPROP 1 LAST BODY_TYPE PLUMBING
J 0
(-245 1282);
DISPLAY 0.340426 (-245 1282);
PAINT GREEN (-245 1282);
DISPLAY INVISIBLE (-245 1282);
FORCEPROP 1 LAST PATH I125
J 0
(-125 1325);
DISPLAY 0.872340 (-125 1325);
PAINT AQUA (-125 1325);
DISPLAY INVISIBLE (-125 1325);
FORCEPROP 1 LAST VOLTAGE 0.0V
J 0
(-245 1282);
DISPLAY 0.340426 (-245 1282);
PAINT GREEN (-245 1282);
DISPLAY INVISIBLE (-245 1282);
FORCEPROP 2 LAST CDS_LIB mstr_symbols
J 0
(-200 1325);
PAINT MONO (-200 1325);
DISPLAY INVISIBLE (-200 1325);
FORCEPROP 1 LAST SIZE 1B
J 0
(-125 1275);
DISPLAY 1.170213 (-125 1275);
PAINT AQUA (-125 1275);
DISPLAY INVISIBLE (-125 1275);
FORCEADD P3V3_STBY..1
(-200 1750);
FORCEPROP 3 LASTPIN (-200 1700) SIG_NAME P3V3_STBY\g
J 0
(-190 1710);
DISPLAY 0.659574 (-190 1710);
PAINT MONO (-190 1710);
DISPLAY INVISIBLE (-190 1710);
FORCEPROP 1 LAST HDL_POWER P3V3_STBY
J 0
(-500 1625);
DISPLAY 0.872340 (-500 1625);
PAINT ORANGE (-500 1625);
DISPLAY INVISIBLE (-500 1625);
FORCEPROP 1 LAST BODY_TYPE PLUMBING
J 0
(-245 1707);
DISPLAY 0.340426 (-245 1707);
PAINT GREEN (-245 1707);
DISPLAY INVISIBLE (-245 1707);
FORCEPROP 1 LAST VOLTAGE 3.3V
J 0
(-245 1707);
DISPLAY 0.340426 (-245 1707);
PAINT GREEN (-245 1707);
DISPLAY INVISIBLE (-245 1707);
FORCEPROP 2 LAST CDS_LIB mstr_symbols
J 0
(-200 1750);
PAINT MONO (-200 1750);
DISPLAY INVISIBLE (-200 1750);
FORCEPROP 1 LAST SIZE 1B
J 0
(-155 1772);
DISPLAY 0.340426 (-155 1772);
PAINT GREEN (-155 1772);
DISPLAY INVISIBLE (-155 1772);
FORCEPROP 1 LAST PATH I126
J 0
(-155 1752);
DISPLAY 0.340426 (-155 1752);
PAINT GREEN (-155 1752);
DISPLAY INVISIBLE (-155 1752);
FORCEADD OFFPAGE..1
(-1750 1900);
FORCEPROP 2 LAST $XR0 155 
J 0
(-2002 1900);
DISPLAY 0.638298 (-2002 1900);
PAINT MONO (-2002 1900);
FORCEPROP 2 LAST CDS_LIB mstr_standard
J 0
(-1750 1900);
PAINT MONO (-1750 1900);
DISPLAY INVISIBLE (-1750 1900);
FORCEPROP 2 LAST PATH I127
J 0
(-2000 1950);
DISPLAY 1.021277 (-2000 1950);
PAINT ORANGE (-2000 1950);
DISPLAY INVISIBLE (-2000 1950);
FORCEPROP 1 LAST OFFPAGE TRUE
J 0
(-1425 1775);
DISPLAY 0.872340 (-1425 1775);
PAINT GREEN (-1425 1775);
DISPLAY INVISIBLE (-1425 1775);
FORCEPROP 1 LAST COMMENT_BODY TRUE
J 0
(-1625 1800);
DISPLAY 0.872340 (-1625 1800);
PAINT GREEN (-1625 1800);
DISPLAY INVISIBLE (-1625 1800);
FORCEADD OFFPAGE..5
(-2600 4600);
FORCEPROP 2 LAST $XR0 176 
J 0
(-2855 4600);
DISPLAY 0.638298 (-2855 4600);
PAINT MONO (-2855 4600);
FORCEPROP 2 LAST CDS_LIB mstr_standard
J 0
(-2600 4600);
PAINT MONO (-2600 4600);
DISPLAY INVISIBLE (-2600 4600);
FORCEPROP 2 LAST PATH I130
J 0
(-2850 4650);
DISPLAY 1.021277 (-2850 4650);
PAINT ORANGE (-2850 4650);
DISPLAY INVISIBLE (-2850 4650);
FORCEPROP 1 LAST OFFPAGE TRUE
J 0
(-2275 4475);
PAINT GREEN (-2275 4475);
DISPLAY INVISIBLE (-2275 4475);
FORCEPROP 1 LAST COMMENT_BODY TRUE
J 0
(-2500 4525);
DISPLAY 0.872340 (-2500 4525);
PAINT PEACH (-2500 4525);
DISPLAY INVISIBLE (-2500 4525);
FORCEADD RES..1
R 5
(-5350 3950);
FORCEPROP 1 LAST LOCATION R1W10
J 0
(-5300 4075);
DISPLAY 0.617021 (-5300 4075);
PAINT AQUA (-5300 4075);
FORCEPROP 1 LAST MATERIAL CHIP
J 0
(-5300 3875);
DISPLAY 0.617021 (-5300 3875);
PAINT SKYBLUE (-5300 3875);
FORCEPROP 1 LAST WATTAGE 1/8W
J 2
(-5200 3925);
DISPLAY 0.617021 (-5200 3925);
PAINT SKYBLUE (-5200 3925);
FORCEPROP 1 LASTPIN (-5350 4050) $PN 1
J 0
(-5338 4013);
DISPLAY 0.787234 (-5338 4013);
PAINT ORANGE (-5338 4013);
FORCEPROP 1 LAST VALUE 0.0
J 2
(-5225 4025);
DISPLAY 0.617021 (-5225 4025);
PAINT SKYBLUE (-5225 4025);
FORCEPROP 1 LAST PACK_TYPE 0805
J 0
(-5300 3775);
DISPLAY 0.617021 (-5300 3775);
PAINT SKYBLUE (-5300 3775);
FORCEPROP 1 LAST TOLERANCE 5%
J 0
(-5300 3975);
DISPLAY 0.617021 (-5300 3975);
PAINT SKYBLUE (-5300 3975);
FORCEPROP 1 LASTPIN (-5350 3850) $PN 2
J 0
(-5338 3838);
DISPLAY 0.787234 (-5338 3838);
PAINT ORANGE (-5338 3838);
FORCEPROP 1 LAST PART_NUMBER G22179-004
J 0
(-5300 3825);
DISPLAY 0.617021 (-5300 3825);
PAINT BLUE (-5300 3825);
FORCEPROP 2 LAST SEC 1
R 2
J 0
(-5375 3825);
DISPLAY 0.680851 (-5375 3825);
PAINT MONO (-5375 3825);
DISPLAY INVISIBLE (-5375 3825);
FORCEPROP 2 LAST SEC_TYPE 0805
R 2
J 0
(-5375 3825);
DISPLAY 1.021277 (-5375 3825);
PAINT ORANGE (-5375 3825);
DISPLAY INVISIBLE (-5375 3825);
FORCEPROP 2 LAST CDS_LIB mstr_discrete
R 3
J 0
(-5350 3950);
PAINT MONO (-5350 3950);
DISPLAY INVISIBLE (-5350 3950);
FORCEPROP 1 LAST PATH I132
R 3
J 0
(-5200 4000);
DISPLAY 0.978723 (-5200 4000);
PAINT WHITE (-5200 4000);
DISPLAY INVISIBLE (-5200 4000);
FORCEPROP 0 LAST ROOM HOT_SWAP
R 3
J 0
(-5150 4000);
DISPLAY 1.021277 (-5150 4000);
PAINT ORANGE (-5150 4000);
DISPLAY INVISIBLE (-5150 4000);
FORCEADD RES..1
R 5
(-4950 3950);
FORCEPROP 1 LAST VALUE 0.0
J 2
(-4825 4025);
DISPLAY 0.638298 (-4825 4025);
PAINT SKYBLUE (-4825 4025);
FORCEPROP 1 LASTPIN (-4950 3850) $PN 2
J 0
(-4938 3838);
DISPLAY 0.787234 (-4938 3838);
PAINT ORANGE (-4938 3838);
FORCEPROP 1 LAST LOCATION R1W11
J 0
(-4900 4075);
DISPLAY 0.638298 (-4900 4075);
PAINT SKYBLUE (-4900 4075);
FORCEPROP 1 LAST MATERIAL EMPTY
J 0
(-4900 3875);
DISPLAY 0.638298 (-4900 3875);
PAINT RED (-4900 3875);
FORCEPROP 1 LAST WATTAGE 1/8W
J 2
(-4800 3925);
DISPLAY 0.638298 (-4800 3925);
PAINT SKYBLUE (-4800 3925);
FORCEPROP 1 LAST TOLERANCE 5%
J 0
(-4900 3975);
DISPLAY 0.638298 (-4900 3975);
PAINT SKYBLUE (-4900 3975);
FORCEPROP 1 LASTPIN (-4950 4050) $PN 1
J 0
(-4938 4013);
DISPLAY 0.787234 (-4938 4013);
PAINT ORANGE (-4938 4013);
FORCEPROP 1 LAST PART_NUMBER G22179-004
J 0
(-4900 3825);
DISPLAY 0.638298 (-4900 3825);
PAINT BLUE (-4900 3825);
FORCEPROP 1 LAST PACK_TYPE 0805
J 0
(-4900 3775);
DISPLAY 0.638298 (-4900 3775);
PAINT SKYBLUE (-4900 3775);
FORCEPROP 2 LAST SEC 1
R 3
J 0
(-4750 4000);
DISPLAY 0.680851 (-4750 4000);
PAINT MONO (-4750 4000);
DISPLAY INVISIBLE (-4750 4000);
FORCEPROP 2 LAST SEC_TYPE 0805
R 3
J 0
(-4750 4000);
DISPLAY 1.021277 (-4750 4000);
PAINT ORANGE (-4750 4000);
DISPLAY INVISIBLE (-4750 4000);
FORCEPROP 2 LAST CDS_LIB mstr_discrete
R 3
J 0
(-4950 3950);
PAINT MONO (-4950 3950);
DISPLAY INVISIBLE (-4950 3950);
FORCEPROP 1 LAST PATH I133
R 3
J 0
(-4800 4000);
DISPLAY 0.978723 (-4800 4000);
PAINT WHITE (-4800 4000);
DISPLAY INVISIBLE (-4800 4000);
FORCEADD P5V_STBY..1
(-5350 4150);
FORCEPROP 3 LASTPIN (-5350 4100) SIG_NAME P5V_STBY\g
J 0
(-5340 4110);
DISPLAY 0.659574 (-5340 4110);
PAINT MONO (-5340 4110);
DISPLAY INVISIBLE (-5340 4110);
FORCEPROP 1 LAST HDL_POWER P5V_STBY
J 0
(-5650 4025);
DISPLAY 0.872340 (-5650 4025);
PAINT ORANGE (-5650 4025);
DISPLAY INVISIBLE (-5650 4025);
FORCEPROP 1 LAST BODY_TYPE PLUMBING
J 0
(-5395 4107);
DISPLAY 0.340426 (-5395 4107);
PAINT GREEN (-5395 4107);
DISPLAY INVISIBLE (-5395 4107);
FORCEPROP 1 LAST VOLTAGE 5.0V
J 0
(-5395 4107);
DISPLAY 0.340426 (-5395 4107);
PAINT SKYBLUE (-5395 4107);
DISPLAY INVISIBLE (-5395 4107);
FORCEPROP 1 LAST SIZE 1B
J 0
(-5305 4172);
DISPLAY 0.340426 (-5305 4172);
PAINT GREEN (-5305 4172);
DISPLAY INVISIBLE (-5305 4172);
FORCEPROP 1 LAST PATH I134
J 0
(-5305 4152);
DISPLAY 0.340426 (-5305 4152);
PAINT GREEN (-5305 4152);
DISPLAY INVISIBLE (-5305 4152);
FORCEPROP 2 LAST CDS_LIB mstr_symbols
J 0
(-5350 4150);
PAINT MONO (-5350 4150);
DISPLAY INVISIBLE (-5350 4150);
FORCEADD OFFPAGE..1
(-6700 3000);
FORCEPROP 2 LAST $XR1 125 
J 0
(-7072 3000);
DISPLAY 0.638298 (-7072 3000);
PAINT MONO (-7072 3000);
FORCEPROP 2 LAST $XR0 119 
J 0
(-6952 3000);
DISPLAY 0.638298 (-6952 3000);
PAINT MONO (-6952 3000);
FORCEPROP 1 LAST COMMENT_BODY TRUE
J 0
(-6575 2900);
DISPLAY 0.872340 (-6575 2900);
PAINT GREEN (-6575 2900);
DISPLAY INVISIBLE (-6575 2900);
FORCEPROP 1 LAST OFFPAGE TRUE
J 0
(-6375 2875);
DISPLAY 0.872340 (-6375 2875);
PAINT GREEN (-6375 2875);
DISPLAY INVISIBLE (-6375 2875);
FORCEPROP 2 LAST CDS_LIB mstr_standard
J 0
(-6700 3000);
PAINT MONO (-6700 3000);
DISPLAY INVISIBLE (-6700 3000);
FORCEPROP 2 LAST PATH I135
J 0
(-6975 3050);
DISPLAY 1.021277 (-6975 3050);
PAINT ORANGE (-6975 3050);
DISPLAY INVISIBLE (-6975 3050);
FORCEADD OFFPAGE..1
(-6700 3225);
FORCEPROP 2 LAST $XR0 190 
J 0
(-6952 3225);
DISPLAY 0.638298 (-6952 3225);
PAINT MONO (-6952 3225);
FORCEPROP 1 LAST COMMENT_BODY TRUE
J 0
(-6575 3125);
DISPLAY 0.872340 (-6575 3125);
PAINT GREEN (-6575 3125);
DISPLAY INVISIBLE (-6575 3125);
FORCEPROP 1 LAST OFFPAGE TRUE
J 0
(-6375 3100);
DISPLAY 0.872340 (-6375 3100);
PAINT GREEN (-6375 3100);
DISPLAY INVISIBLE (-6375 3100);
FORCEPROP 2 LAST PATH I136
J 0
(-6975 3275);
DISPLAY 1.021277 (-6975 3275);
PAINT ORANGE (-6975 3275);
DISPLAY INVISIBLE (-6975 3275);
FORCEPROP 2 LAST CDS_LIB mstr_standard
J 0
(-6700 3225);
PAINT MONO (-6700 3225);
DISPLAY INVISIBLE (-6700 3225);
FORCEADD RES..1
(-5650 3225);
FORCEPROP 1 LAST PART_NUMBER G21497-005
J 0
(-5650 3300);
DISPLAY 0.617021 (-5650 3300);
PAINT BLUE (-5650 3300);
FORCEPROP 1 LAST LOCATION R1W12
J 0
(-5800 3300);
DISPLAY 0.617021 (-5800 3300);
PAINT AQUA (-5800 3300);
FORCEPROP 1 LAST VALUE 0.0
J 2
(-5800 3150);
DISPLAY 0.617021 (-5800 3150);
PAINT SKYBLUE (-5800 3150);
FORCEPROP 1 LAST MATERIAL CHIP
J 0
(-5600 3150);
DISPLAY 0.510638 (-5600 3150);
PAINT SKYBLUE (-5600 3150);
FORCEPROP 1 LASTPIN (-5750 3225) $PN 1
J 0
(-5738 3237);
DISPLAY 0.787234 (-5738 3237);
PAINT ORANGE (-5738 3237);
FORCEPROP 1 LAST TOLERANCE 5%
J 0
(-5775 3150);
DISPLAY 0.617021 (-5775 3150);
PAINT SKYBLUE (-5775 3150);
FORCEPROP 1 LASTPIN (-5550 3225) $PN 2
J 0
(-5588 3237);
DISPLAY 0.787234 (-5588 3237);
PAINT ORANGE (-5588 3237);
FORCEPROP 1 LAST WATTAGE 1/16W
J 0
(-5500 3150);
DISPLAY 0.510638 (-5500 3150);
PAINT SKYBLUE (-5500 3150);
FORCEPROP 1 LAST PACK_TYPE 0402
J 0
(-5700 3150);
DISPLAY 0.617021 (-5700 3150);
PAINT SKYBLUE (-5700 3150);
FORCEPROP 2 LAST SEC 1
J 0
(-5700 3425);
DISPLAY 0.680851 (-5700 3425);
PAINT MONO (-5700 3425);
DISPLAY INVISIBLE (-5700 3425);
FORCEPROP 2 LAST SEC_TYPE 0402
J 0
(-5700 3425);
DISPLAY 1.021277 (-5700 3425);
PAINT ORANGE (-5700 3425);
DISPLAY INVISIBLE (-5700 3425);
FORCEPROP 2 LAST CDS_LIB mstr_discrete
J 0
(-5650 3225);
PAINT MONO (-5650 3225);
DISPLAY INVISIBLE (-5650 3225);
FORCEPROP 1 LAST PATH I137
J 0
(-5700 3375);
DISPLAY 0.978723 (-5700 3375);
PAINT WHITE (-5700 3375);
DISPLAY INVISIBLE (-5700 3375);
FORCEPROP 2 LAST ROOM CPU0
J 0
(-5700 3375);
PAINT PEACH (-5700 3375);
DISPLAY INVISIBLE (-5700 3375);
FORCEPROP 2 LAST BOM_COST PROC_SIDEBAND
J 0
(-5650 3225);
PAINT MONO (-5650 3225);
DISPLAY INVISIBLE (-5650 3225);
FORCEADD RES..1
(-5650 3000);
FORCEPROP 0 LAST POP NOPOP
J 0
(-5750 2875);
DISPLAY 1.021277 (-5750 2875);
PAINT RED (-5750 2875);
FORCEPROP 1 LAST WATTAGE 1/16W
J 0
(-5500 2925);
DISPLAY 0.510638 (-5500 2925);
PAINT SKYBLUE (-5500 2925);
FORCEPROP 1 LAST PACK_TYPE 0402
J 0
(-5700 2925);
DISPLAY 0.617021 (-5700 2925);
PAINT SKYBLUE (-5700 2925);
FORCEPROP 1 LAST VALUE 0.0
J 2
(-5800 2925);
DISPLAY 0.617021 (-5800 2925);
PAINT SKYBLUE (-5800 2925);
FORCEPROP 1 LAST LOCATION R1W13
J 0
(-5800 3075);
DISPLAY 0.617021 (-5800 3075);
PAINT AQUA (-5800 3075);
FORCEPROP 1 LASTPIN (-5750 3000) $PN 1
J 0
(-5738 3012);
DISPLAY 0.787234 (-5738 3012);
PAINT ORANGE (-5738 3012);
FORCEPROP 1 LAST TOLERANCE 5%
J 0
(-5775 2925);
DISPLAY 0.617021 (-5775 2925);
PAINT SKYBLUE (-5775 2925);
FORCEPROP 1 LAST MATERIAL CHIP
J 0
(-5600 2925);
DISPLAY 0.510638 (-5600 2925);
PAINT SKYBLUE (-5600 2925);
FORCEPROP 1 LASTPIN (-5550 3000) $PN 2
J 0
(-5588 3012);
DISPLAY 0.787234 (-5588 3012);
PAINT ORANGE (-5588 3012);
FORCEPROP 1 LAST PART_NUMBER G21497-005
J 0
(-5650 3075);
DISPLAY 0.617021 (-5650 3075);
PAINT BLUE (-5650 3075);
FORCEPROP 2 LAST SEC 1
J 0
(-5700 3200);
DISPLAY 0.680851 (-5700 3200);
PAINT MONO (-5700 3200);
DISPLAY INVISIBLE (-5700 3200);
FORCEPROP 2 LAST SEC_TYPE 0402
J 0
(-5700 3200);
DISPLAY 1.021277 (-5700 3200);
PAINT ORANGE (-5700 3200);
DISPLAY INVISIBLE (-5700 3200);
FORCEPROP 2 LAST CDS_LIB mstr_discrete
J 0
(-5650 3000);
PAINT MONO (-5650 3000);
DISPLAY INVISIBLE (-5650 3000);
FORCEPROP 1 LAST PATH I138
J 0
(-5700 3150);
DISPLAY 0.978723 (-5700 3150);
PAINT WHITE (-5700 3150);
DISPLAY INVISIBLE (-5700 3150);
FORCEPROP 2 LAST ROOM CPU0
J 0
(-5700 3150);
PAINT PEACH (-5700 3150);
DISPLAY INVISIBLE (-5700 3150);
FORCEPROP 2 LAST BOM_COST PROC_SIDEBAND
J 0
(-5650 3000);
PAINT MONO (-5650 3000);
DISPLAY INVISIBLE (-5650 3000);
FORCEADD CAP_A..1
(-200 1500);
FORCEPROP 1 LAST LOCATION C6W10
J 0
(-150 1600);
DISPLAY 0.617021 (-150 1600);
PAINT AQUA (-150 1600);
FORCEPROP 1 LAST VALUE 0.1UF
J 0
(-150 1550);
DISPLAY 0.617021 (-150 1550);
PAINT SKYBLUE (-150 1550);
FORCEPROP 1 LASTPIN (-200 1600) $PN 1
J 0
(-190 1580);
DISPLAY 0.617021 (-190 1580);
PAINT ORANGE (-190 1580);
FORCEPROP 1 LAST VOLTAGE 16V
J 0
(-150 1500);
DISPLAY 0.617021 (-150 1500);
PAINT SKYBLUE (-150 1500);
FORCEPROP 1 LAST TOLERANCE 10%
J 0
(-150 1450);
DISPLAY 0.617021 (-150 1450);
PAINT SKYBLUE (-150 1450);
FORCEPROP 1 LAST MATERIAL X7R
J 0
(-150 1400);
DISPLAY 0.617021 (-150 1400);
PAINT SKYBLUE (-150 1400);
FORCEPROP 1 LAST PACK_TYPE 0402V
J 0
(-150 1300);
DISPLAY 0.617021 (-150 1300);
PAINT SKYBLUE (-150 1300);
FORCEPROP 1 LASTPIN (-200 1400) $PN 2
J 0
(-190 1380);
DISPLAY 0.617021 (-190 1380);
PAINT ORANGE (-190 1380);
FORCEPROP 1 LAST PART_NUMBER A36096-030
J 0
(-150 1350);
DISPLAY 0.617021 (-150 1350);
PAINT BLUE (-150 1350);
FORCEPROP 2 LAST SEC 1
J 0
(-150 1725);
DISPLAY 0.680851 (-150 1725);
PAINT MONO (-150 1725);
DISPLAY INVISIBLE (-150 1725);
FORCEPROP 2 LAST SEC_TYPE 0402V
J 0
(-150 1725);
DISPLAY 1.021277 (-150 1725);
PAINT ORANGE (-150 1725);
DISPLAY INVISIBLE (-150 1725);
FORCEPROP 2 LAST ROOM VDDQ_KLM_PWR_VR
J 0
(-150 1650);
DISPLAY 1.361702 (-150 1650);
PAINT ORANGE (-150 1650);
DISPLAY INVISIBLE (-150 1650);
FORCEPROP 2 LAST CDS_SEC 1
J 0
(-150 1650);
PAINT ORANGE (-150 1650);
DISPLAY INVISIBLE (-150 1650);
FORCEPROP 2 LAST CDS_LIB dev_discrete
J 0
(-200 1500);
PAINT ORANGE (-200 1500);
DISPLAY INVISIBLE (-200 1500);
FORCEPROP 1 LAST PATH I139
J 0
(-150 1650);
DISPLAY 0.978723 (-150 1650);
PAINT WHITE (-150 1650);
DISPLAY INVISIBLE (-150 1650);
FORCEPROP 2 LAST CDS_LOCATION C6W10
J 0
(-150 1600);
DISPLAY 0.617021 (-150 1600);
PAINT AQUA (-150 1600);
DISPLAY INVISIBLE (-150 1600);
FORCEADD P3V3_STBY..1
(-1550 1800);
FORCEPROP 3 LASTPIN (-1550 1750) SIG_NAME P3V3_STBY\g
J 0
(-1540 1760);
DISPLAY 0.659574 (-1540 1760);
PAINT MONO (-1540 1760);
DISPLAY INVISIBLE (-1540 1760);
FORCEPROP 1 LAST PATH I140
J 0
(-1505 1802);
DISPLAY 0.340426 (-1505 1802);
PAINT GREEN (-1505 1802);
DISPLAY INVISIBLE (-1505 1802);
FORCEPROP 1 LAST SIZE 1B
J 0
(-1505 1822);
DISPLAY 0.340426 (-1505 1822);
PAINT GREEN (-1505 1822);
DISPLAY INVISIBLE (-1505 1822);
FORCEPROP 1 LAST BODY_TYPE PLUMBING
J 0
(-1595 1757);
DISPLAY 0.340426 (-1595 1757);
PAINT GREEN (-1595 1757);
DISPLAY INVISIBLE (-1595 1757);
FORCEPROP 2 LAST CDS_LIB mstr_symbols
J 0
(-1550 1800);
PAINT ORANGE (-1550 1800);
DISPLAY INVISIBLE (-1550 1800);
FORCEPROP 1 LAST VOLTAGE 3.3V
J 0
(-1595 1757);
DISPLAY 0.340426 (-1595 1757);
PAINT SKYBLUE (-1595 1757);
DISPLAY INVISIBLE (-1595 1757);
FORCEPROP 1 LAST HDL_POWER P3V3_STBY
J 0
(-1850 1675);
DISPLAY 0.872340 (-1850 1675);
PAINT ORANGE (-1850 1675);
DISPLAY INVISIBLE (-1850 1675);
FORCEADD RES..1
(-1350 3900);
FORCEPROP 1 LAST LOCATION R1W33
J 0
(-1800 3950);
DISPLAY 0.617021 (-1800 3950);
PAINT AQUA (-1800 3950);
FORCEPROP 1 LAST PART_NUMBER G21497-005
J 0
(-1625 3950);
DISPLAY 0.617021 (-1625 3950);
PAINT BLUE (-1625 3950);
FORCEPROP 1 LAST PACK_TYPE 0402
J 0
(-1100 3950);
DISPLAY 0.617021 (-1100 3950);
PAINT SKYBLUE (-1100 3950);
FORCEPROP 1 LASTPIN (-1450 3900) $PN 1
J 0
(-1438 3912);
DISPLAY 0.617021 (-1438 3912);
PAINT WHITE (-1438 3912);
FORCEPROP 1 LAST VALUE 0.0
J 0
(-1300 3950);
DISPLAY 0.617021 (-1300 3950);
PAINT SKYBLUE (-1300 3950);
FORCEPROP 1 LASTPIN (-1250 3900) $PN 2
J 0
(-1288 3912);
DISPLAY 0.617021 (-1288 3912);
PAINT WHITE (-1288 3912);
FORCEPROP 1 LAST TOLERANCE 5%
J 0
(-1200 3950);
DISPLAY 0.617021 (-1200 3950);
PAINT SKYBLUE (-1200 3950);
FORCEPROP 1 LAST WATTAGE 1/16W
J 0
(-950 3950);
DISPLAY 0.638298 (-950 3950);
PAINT SKYBLUE (-950 3950);
FORCEPROP 2 LAST CDS_LOCATION R1W33
J 0
(-1825 3900);
DISPLAY 0.617021 (-1825 3900);
PAINT AQUA (-1825 3900);
DISPLAY INVISIBLE (-1825 3900);
FORCEPROP 2 LAST SEC 1
J 0
(-1400 4125);
DISPLAY 0.680851 (-1400 4125);
PAINT MONO (-1400 4125);
DISPLAY INVISIBLE (-1400 4125);
FORCEPROP 2 LAST SEC_TYPE 0402
J 0
(-1400 4125);
DISPLAY 1.021277 (-1400 4125);
PAINT ORANGE (-1400 4125);
DISPLAY INVISIBLE (-1400 4125);
FORCEPROP 2 LAST ROOM CPU0
J 0
(-1400 4050);
PAINT PEACH (-1400 4050);
DISPLAY INVISIBLE (-1400 4050);
FORCEPROP 1 LAST MATERIAL CHIP
J 0
(-1200 3800);
DISPLAY 0.510638 (-1200 3800);
PAINT SKYBLUE (-1200 3800);
DISPLAY INVISIBLE (-1200 3800);
FORCEPROP 2 LAST BOM_COST PROC_SIDEBAND
J 0
(-1350 3900);
PAINT MONO (-1350 3900);
DISPLAY INVISIBLE (-1350 3900);
FORCEPROP 2 LAST CDS_LIB mstr_discrete
J 0
(-1350 3900);
DISPLAY 1.340426 (-1350 3900);
PAINT ORANGE (-1350 3900);
DISPLAY INVISIBLE (-1350 3900);
FORCEPROP 1 LAST PATH I142
J 0
(-1400 4050);
DISPLAY 0.978723 (-1400 4050);
PAINT WHITE (-1400 4050);
DISPLAY INVISIBLE (-1400 4050);
FORCEADD RES..1
(-1350 3850);
FORCEPROP 1 LAST LOCATION R1W34
J 0
(-1800 3800);
DISPLAY 0.617021 (-1800 3800);
PAINT AQUA (-1800 3800);
FORCEPROP 1 LAST WATTAGE 1/16W
J 0
(-950 3800);
DISPLAY 0.638298 (-950 3800);
PAINT SKYBLUE (-950 3800);
FORCEPROP 1 LAST TOLERANCE 5%
J 0
(-1200 3800);
DISPLAY 0.617021 (-1200 3800);
PAINT SKYBLUE (-1200 3800);
FORCEPROP 1 LASTPIN (-1450 3850) $PN 1
J 0
(-1438 3862);
DISPLAY 0.617021 (-1438 3862);
PAINT WHITE (-1438 3862);
FORCEPROP 1 LASTPIN (-1250 3850) $PN 2
J 0
(-1288 3862);
DISPLAY 0.617021 (-1288 3862);
PAINT WHITE (-1288 3862);
FORCEPROP 1 LAST PACK_TYPE 0402
J 0
(-1100 3800);
DISPLAY 0.617021 (-1100 3800);
PAINT SKYBLUE (-1100 3800);
FORCEPROP 1 LAST VALUE 0.0
J 0
(-1300 3800);
DISPLAY 0.617021 (-1300 3800);
PAINT SKYBLUE (-1300 3800);
FORCEPROP 1 LAST PART_NUMBER G21497-005
J 0
(-1625 3800);
DISPLAY 0.617021 (-1625 3800);
PAINT BLUE (-1625 3800);
FORCEPROP 2 LAST CDS_LOCATION R1W34
J 0
(-1825 3850);
DISPLAY 0.617021 (-1825 3850);
PAINT AQUA (-1825 3850);
DISPLAY INVISIBLE (-1825 3850);
FORCEPROP 2 LAST SEC 1
J 0
(-1400 4075);
DISPLAY 0.680851 (-1400 4075);
PAINT MONO (-1400 4075);
DISPLAY INVISIBLE (-1400 4075);
FORCEPROP 2 LAST SEC_TYPE 0402
J 0
(-1400 4075);
DISPLAY 1.021277 (-1400 4075);
PAINT ORANGE (-1400 4075);
DISPLAY INVISIBLE (-1400 4075);
FORCEPROP 2 LAST ROOM CPU0
J 0
(-1400 4000);
PAINT PEACH (-1400 4000);
DISPLAY INVISIBLE (-1400 4000);
FORCEPROP 1 LAST MATERIAL CHIP
J 0
(-1200 3750);
DISPLAY 0.510638 (-1200 3750);
PAINT SKYBLUE (-1200 3750);
DISPLAY INVISIBLE (-1200 3750);
FORCEPROP 2 LAST BOM_COST PROC_SIDEBAND
J 0
(-1350 3850);
PAINT MONO (-1350 3850);
DISPLAY INVISIBLE (-1350 3850);
FORCEPROP 2 LAST CDS_LIB mstr_discrete
J 0
(-1350 3850);
DISPLAY 1.340426 (-1350 3850);
PAINT ORANGE (-1350 3850);
DISPLAY INVISIBLE (-1350 3850);
FORCEPROP 1 LAST PATH I143
J 0
(-1400 4000);
DISPLAY 0.978723 (-1400 4000);
PAINT WHITE (-1400 4000);
DISPLAY INVISIBLE (-1400 4000);
FORCEADD OFFPAGE..4
(-350 3900);
FORCEPROP 2 LAST $XR1 247 
J 0
(-44 3900);
DISPLAY 0.638298 (-44 3900);
PAINT MONO (-44 3900);
FORCEPROP 2 LAST $XR0 145 
J 0
(-164 3900);
DISPLAY 0.638298 (-164 3900);
PAINT MONO (-164 3900);
FORCEPROP 2 LAST PATH I144
J 0
(0 3950);
DISPLAY 1.021277 (0 3950);
PAINT ORANGE (0 3950);
DISPLAY INVISIBLE (0 3950);
FORCEPROP 1 LAST COMMENT_BODY TRUE
J 0
(-375 3800);
DISPLAY 0.872340 (-375 3800);
PAINT GREEN (-375 3800);
DISPLAY INVISIBLE (-375 3800);
FORCEPROP 1 LAST OFFPAGE TRUE
J 0
(-25 3775);
DISPLAY 0.872340 (-25 3775);
PAINT GREEN (-25 3775);
DISPLAY INVISIBLE (-25 3775);
FORCEPROP 2 LAST CDS_LIB mstr_standard
J 0
(-350 3900);
PAINT MONO (-350 3900);
DISPLAY INVISIBLE (-350 3900);
FORCEADD OFFPAGE..3
(-350 3850);
FORCEPROP 2 LAST $XR1 247 
J 0
(-16 3850);
DISPLAY 0.638298 (-16 3850);
PAINT MONO (-16 3850);
FORCEPROP 2 LAST $XR0 145 
J 0
(-136 3850);
DISPLAY 0.638298 (-136 3850);
PAINT MONO (-136 3850);
FORCEPROP 2 LAST PATH I145
J 0
(0 3900);
DISPLAY 1.021277 (0 3900);
PAINT ORANGE (0 3900);
DISPLAY INVISIBLE (0 3900);
FORCEPROP 1 LAST COMMENT_BODY TRUE
J 0
(-400 3750);
DISPLAY 0.872340 (-400 3750);
PAINT GREEN (-400 3750);
DISPLAY INVISIBLE (-400 3750);
FORCEPROP 1 LAST OFFPAGE TRUE
J 0
(-25 3725);
DISPLAY 0.872340 (-25 3725);
PAINT GREEN (-25 3725);
DISPLAY INVISIBLE (-25 3725);
FORCEPROP 2 LAST CDS_LIB mstr_standard
J 0
(-350 3850);
PAINT MONO (-350 3850);
DISPLAY INVISIBLE (-350 3850);
FORCEADD TTL1G126_A..1
R 6
(-2500 1400);
FORCEPROP 1 LAST PART_NUMBER A79322-001
J 0
(-2400 1461);
DISPLAY 0.617021 (-2400 1461);
PAINT BLUE (-2400 1461);
FORCEPROP 1 LAST LOCATION U6W4
J 0
(-2400 1571);
DISPLAY 0.617021 (-2400 1571);
PAINT AQUA (-2400 1571);
FORCEPROP 1 LAST MATERIAL IC
J 0
(-2250 1296);
DISPLAY 0.617021 (-2250 1296);
PAINT SKYBLUE (-2250 1296);
FORCEPROP 1 LAST VALUE 74HC1G126
J 0
(-2475 1296);
DISPLAY 0.617021 (-2475 1296);
PAINT SKYBLUE (-2475 1296);
FORCEPROP 1 LASTPIN (-2650 1400) $PN 2
J 2
(-2625 1361);
DISPLAY 0.617021 (-2625 1361);
PAINT WHITE (-2625 1361);
FORCEPROP 1 LASTPIN (-2500 1500) $PN 1
J 0
(-2495 1521);
DISPLAY 0.617021 (-2495 1521);
PAINT WHITE (-2495 1521);
FORCEPROP 1 LASTPIN (-2350 1400) $PN 4
J 0
(-2385 1361);
DISPLAY 0.617021 (-2385 1361);
PAINT WHITE (-2385 1361);
FORCEPROP 1 LAST POWER_GROUP VCC=P3V3_STBY;GND=GND;
J 0
(-2400 1511);
DISPLAY 0.617021 (-2400 1511);
PAINT ORANGE (-2400 1511);
FORCEPROP 1 LAST PATH I146
J 2
(-2605 1254);
DISPLAY 0.978723 (-2605 1254);
PAINT GREEN (-2605 1254);
DISPLAY INVISIBLE (-2605 1254);
FORCEPROP 1 LAST PACK_TYPE SOT
J 0
(-2550 1104);
DISPLAY 0.978723 (-2550 1104);
PAINT SKYBLUE (-2550 1104);
DISPLAY INVISIBLE (-2550 1104);
FORCEPROP 2 LAST ROOM SB
J 0
(-2550 1102);
DISPLAY 1.021277 (-2550 1102);
PAINT ORANGE (-2550 1102);
DISPLAY INVISIBLE (-2550 1102);
FORCEPROP 2 LAST SEC 1
J 0
(-2550 1118);
DISPLAY 0.680851 (-2550 1118);
PAINT MONO (-2550 1118);
DISPLAY INVISIBLE (-2550 1118);
FORCEPROP 2 LAST CDS_LIB mstr_ttl
J 0
(-2500 1353);
PAINT MONO (-2500 1353);
DISPLAY INVISIBLE (-2500 1353);
FORCEPROP 2 LAST SEC_TYPE SOT
J 0
(-2550 1102);
DISPLAY 1.021277 (-2550 1102);
PAINT ORANGE (-2550 1102);
DISPLAY INVISIBLE (-2550 1102);
FORCEPROP 2 LAST BOM_COST SB
J 0
(-2550 1052);
DISPLAY 1.021277 (-2550 1052);
PAINT ORANGE (-2550 1052);
DISPLAY INVISIBLE (-2550 1052);
FORCEPROP 2 LAST CDS_LOCATION U6W4
J 0
(-2550 1171);
DISPLAY 0.617021 (-2550 1171);
PAINT AQUA (-2550 1171);
DISPLAY INVISIBLE (-2550 1171);
FORCEADD RES..2
(-1550 1600);
FORCEPROP 1 LAST TOLERANCE 1%
J 0
(-1505 1625);
DISPLAY 0.617021 (-1505 1625);
PAINT SKYBLUE (-1505 1625);
FORCEPROP 1 LAST MATERIAL CHIP
J 0
(-1510 1525);
DISPLAY 0.617021 (-1510 1525);
PAINT SKYBLUE (-1510 1525);
FORCEPROP 1 LAST PART_NUMBER G22026-050
J 0
(-1510 1475);
DISPLAY 0.617021 (-1510 1475);
PAINT BLUE (-1510 1475);
FORCEPROP 1 LASTPIN (-1550 1500) $PN 2
J 0
(-1545 1510);
DISPLAY 0.617021 (-1545 1510);
PAINT ORANGE (-1545 1510);
FORCEPROP 1 LAST PACK_TYPE 0603
J 0
(-1510 1425);
DISPLAY 0.617021 (-1510 1425);
PAINT SKYBLUE (-1510 1425);
FORCEPROP 1 LAST WATTAGE 1/10W
J 0
(-1510 1575);
DISPLAY 0.617021 (-1510 1575);
PAINT SKYBLUE (-1510 1575);
FORCEPROP 1 LASTPIN (-1550 1700) $PN 1
J 0
(-1545 1662);
DISPLAY 0.617021 (-1545 1662);
PAINT ORANGE (-1545 1662);
FORCEPROP 1 LAST VALUE 100.0K
J 0
(-1505 1675);
DISPLAY 0.617021 (-1505 1675);
PAINT SKYBLUE (-1505 1675);
FORCEPROP 1 LAST LOCATION R6W30
J 0
(-1500 1725);
DISPLAY 0.617021 (-1500 1725);
PAINT AQUA (-1500 1725);
FORCEPROP 1 LAST PATH I147
J 0
(-1500 1775);
DISPLAY 0.978723 (-1500 1775);
PAINT WHITE (-1500 1775);
DISPLAY INVISIBLE (-1500 1775);
FORCEPROP 2 LAST CDS_LIB mstr_discrete
J 0
(-1550 1600);
PAINT ORANGE (-1550 1600);
DISPLAY INVISIBLE (-1550 1600);
FORCEPROP 2 LAST ROOM CPU0
J 0
(-1475 1700);
DISPLAY 1.021277 (-1475 1700);
PAINT ORANGE (-1475 1700);
DISPLAY INVISIBLE (-1475 1700);
FORCEPROP 2 LAST BOM_COST PROC_SOCKET
J 0
(-1475 1750);
DISPLAY 1.021277 (-1475 1750);
PAINT ORANGE (-1475 1750);
DISPLAY INVISIBLE (-1475 1750);
FORCEPROP 2 LAST SEC 1
J 0
(-1500 1825);
DISPLAY 0.680851 (-1500 1825);
PAINT MONO (-1500 1825);
DISPLAY INVISIBLE (-1500 1825);
FORCEPROP 2 LAST SEC_TYPE 0603
J 0
(-1500 1825);
DISPLAY 1.021277 (-1500 1825);
PAINT ORANGE (-1500 1825);
DISPLAY INVISIBLE (-1500 1825);
FORCEPROP 2 LAST CDS_LOCATION R6W30
J 0
(-1500 1725);
DISPLAY 0.617021 (-1500 1725);
PAINT AQUA (-1500 1725);
DISPLAY INVISIBLE (-1500 1725);
FORCEADD TTL1G126_A..1
R 6
(-1550 3150);
FORCEPROP 1 LAST VALUE 74HC1G126
J 0
(-1525 3046);
DISPLAY 0.617021 (-1525 3046);
PAINT SKYBLUE (-1525 3046);
FORCEPROP 1 LAST PART_NUMBER A79322-001
J 0
(-1450 3211);
DISPLAY 0.617021 (-1450 3211);
PAINT BLUE (-1450 3211);
FORCEPROP 1 LASTPIN (-1550 3250) $PN 1
J 0
(-1545 3271);
DISPLAY 0.617021 (-1545 3271);
PAINT WHITE (-1545 3271);
FORCEPROP 1 LASTPIN (-1700 3150) $PN 2
J 2
(-1675 3111);
DISPLAY 0.617021 (-1675 3111);
PAINT WHITE (-1675 3111);
FORCEPROP 1 LASTPIN (-1400 3150) $PN 4
J 0
(-1435 3111);
DISPLAY 0.617021 (-1435 3111);
PAINT WHITE (-1435 3111);
FORCEPROP 1 LAST MATERIAL IC
J 0
(-1300 3046);
DISPLAY 0.617021 (-1300 3046);
PAINT SKYBLUE (-1300 3046);
FORCEPROP 1 LAST LOCATION U6W5
J 0
(-1450 3321);
DISPLAY 0.617021 (-1450 3321);
PAINT AQUA (-1450 3321);
FORCEPROP 1 LAST POWER_GROUP VCC=P3V3_STBY;GND=GND;
J 0
(-1450 3261);
DISPLAY 0.617021 (-1450 3261);
PAINT ORANGE (-1450 3261);
FORCEPROP 1 LAST PATH I148
J 2
(-1655 3050);
DISPLAY 0.978723 (-1655 3050);
PAINT GREEN (-1655 3050);
DISPLAY INVISIBLE (-1655 3050);
FORCEPROP 1 LAST PACK_TYPE SOT
J 0
(-1600 2854);
DISPLAY 0.978723 (-1600 2854);
PAINT SKYBLUE (-1600 2854);
DISPLAY INVISIBLE (-1600 2854);
FORCEPROP 2 LAST ROOM SB
J 0
(-1600 2852);
DISPLAY 1.021277 (-1600 2852);
PAINT ORANGE (-1600 2852);
DISPLAY INVISIBLE (-1600 2852);
FORCEPROP 2 LAST SEC 1
J 0
(-1600 2868);
DISPLAY 0.680851 (-1600 2868);
PAINT MONO (-1600 2868);
DISPLAY INVISIBLE (-1600 2868);
FORCEPROP 2 LAST CDS_LIB mstr_ttl
J 0
(-1550 3103);
PAINT MONO (-1550 3103);
DISPLAY INVISIBLE (-1550 3103);
FORCEPROP 2 LAST SEC_TYPE SOT
J 0
(-1600 2852);
DISPLAY 1.021277 (-1600 2852);
PAINT ORANGE (-1600 2852);
DISPLAY INVISIBLE (-1600 2852);
FORCEPROP 2 LAST BOM_COST SB
J 0
(-1600 2802);
DISPLAY 1.021277 (-1600 2802);
PAINT ORANGE (-1600 2802);
DISPLAY INVISIBLE (-1600 2802);
FORCEPROP 2 LAST CDS_LOCATION U6W5
J 0
(-1600 2921);
DISPLAY 0.617021 (-1600 2921);
PAINT AQUA (-1600 2921);
DISPLAY INVISIBLE (-1600 2921);
FORCEADD OFFPAGE..1
(-2325 3150);
FORCEPROP 2 LAST $XR1 181 
J 0
(-2697 3150);
DISPLAY 0.638298 (-2697 3150);
PAINT MONO (-2697 3150);
FORCEPROP 2 LAST $XR0 158 
J 0
(-2577 3150);
DISPLAY 0.638298 (-2577 3150);
PAINT MONO (-2577 3150);
FORCEPROP 2 LAST CDS_LIB mstr_standard
J 0
(-2325 3150);
PAINT MONO (-2325 3150);
DISPLAY INVISIBLE (-2325 3150);
FORCEPROP 1 LAST OFFPAGE TRUE
J 0
(-2000 3025);
DISPLAY 0.872340 (-2000 3025);
PAINT GREEN (-2000 3025);
DISPLAY INVISIBLE (-2000 3025);
FORCEPROP 1 LAST COMMENT_BODY TRUE
J 0
(-2200 3050);
DISPLAY 0.872340 (-2200 3050);
PAINT GREEN (-2200 3050);
DISPLAY INVISIBLE (-2200 3050);
FORCEPROP 2 LAST PATH I149
J 0
(-2600 3200);
DISPLAY 1.021277 (-2600 3200);
PAINT ORANGE (-2600 3200);
DISPLAY INVISIBLE (-2600 3200);
FORCEADD GND..1
(-750 3425);
FORCEPROP 3 LASTPIN (-750 3475) SIG_NAME GND\g
J 0
(-740 3485);
DISPLAY 0.659574 (-740 3485);
PAINT MONO (-740 3485);
DISPLAY INVISIBLE (-740 3485);
FORCEPROP 2 LAST CDS_LIB mstr_symbols
J 0
(-750 3425);
PAINT ORANGE (-750 3425);
DISPLAY INVISIBLE (-750 3425);
FORCEPROP 1 LAST SIZE 1B
J 0
(-675 3375);
DISPLAY 0.872340 (-675 3375);
PAINT AQUA (-675 3375);
DISPLAY INVISIBLE (-675 3375);
FORCEPROP 1 LAST VOLTAGE 0.0V
J 0
(-795 3382);
DISPLAY 0.340426 (-795 3382);
PAINT SKYBLUE (-795 3382);
DISPLAY INVISIBLE (-795 3382);
FORCEPROP 1 LAST BODY_TYPE PLUMBING
J 0
(-795 3382);
DISPLAY 0.340426 (-795 3382);
PAINT GREEN (-795 3382);
DISPLAY INVISIBLE (-795 3382);
FORCEPROP 1 LAST HDL_POWER GND
J 0
(-750 3575);
DISPLAY 0.702128 (-750 3575);
PAINT GREEN (-750 3575);
DISPLAY INVISIBLE (-750 3575);
FORCEPROP 1 LAST PATH I151
J 0
(-675 3425);
DISPLAY 0.872340 (-675 3425);
PAINT AQUA (-675 3425);
DISPLAY INVISIBLE (-675 3425);
FORCEADD OFFPAGE..2
(-25 2600);
FORCEPROP 2 LAST $XR0 155 
J 0
(164 2600);
DISPLAY 0.638298 (164 2600);
PAINT MONO (164 2600);
FORCEPROP 2 LAST PATH I155
J 0
(175 2650);
DISPLAY 1.021277 (175 2650);
PAINT ORANGE (175 2650);
DISPLAY INVISIBLE (175 2650);
FORCEPROP 1 LAST COMMENT_BODY TRUE
J 0
(-70 2505);
DISPLAY 0.872340 (-70 2505);
PAINT GREEN (-70 2505);
DISPLAY INVISIBLE (-70 2505);
FORCEPROP 1 LAST OFFPAGE TRUE
J 0
(300 2475);
DISPLAY 0.872340 (300 2475);
PAINT GREEN (300 2475);
DISPLAY INVISIBLE (300 2475);
FORCEPROP 2 LAST CDS_LIB mstr_standard
J 0
(-25 2600);
PAINT MONO (-25 2600);
DISPLAY INVISIBLE (-25 2600);
FORCEADD RES..2
R 1
(-1250 3525);
FORCEPROP 1 LAST TOLERANCE 1%
J 0
(-1425 3420);
DISPLAY 0.617021 (-1425 3420);
PAINT SKYBLUE (-1425 3420);
FORCEPROP 1 LAST LOCATION R6W38
J 0
(-1400 3570);
DISPLAY 0.617021 (-1400 3570);
PAINT AQUA (-1400 3570);
FORCEPROP 1 LAST VALUE 20.0K
J 0
(-1425 3470);
DISPLAY 0.617021 (-1425 3470);
PAINT SKYBLUE (-1425 3470);
FORCEPROP 1 LASTPIN (-1150 3525) $PN 2
J 0
(-1160 3530);
DISPLAY 0.617021 (-1160 3530);
PAINT ORANGE (-1160 3530);
FORCEPROP 1 LAST WATTAGE 1/16W
J 0
(-1300 3465);
DISPLAY 0.617021 (-1300 3465);
PAINT SKYBLUE (-1300 3465);
FORCEPROP 1 LAST PACK_TYPE 0402
J 0
(-1150 3415);
DISPLAY 0.617021 (-1150 3415);
PAINT SKYBLUE (-1150 3415);
FORCEPROP 1 LASTPIN (-1350 3525) $PN 1
J 0
(-1362 3530);
DISPLAY 0.617021 (-1362 3530);
PAINT ORANGE (-1362 3530);
FORCEPROP 1 LAST PART_NUMBER G21796-040
J 0
(-1150 3465);
DISPLAY 0.617021 (-1150 3465);
PAINT BLUE (-1150 3465);
FORCEPROP 1 LAST MATERIAL CHIP
J 0
(-1300 3415);
DISPLAY 0.617021 (-1300 3415);
PAINT SKYBLUE (-1300 3415);
FORCEPROP 2 LAST CDS_LOCATION R6W38
R 1
J 0
(-1375 3570);
DISPLAY 0.617021 (-1375 3570);
PAINT AQUA (-1375 3570);
DISPLAY INVISIBLE (-1375 3570);
FORCEPROP 1 LAST PATH I156
R 1
J 0
(-1425 3575);
DISPLAY 0.978723 (-1425 3575);
PAINT WHITE (-1425 3575);
DISPLAY INVISIBLE (-1425 3575);
FORCEPROP 2 LAST SEC 1
R 1
J 0
(-1475 3575);
DISPLAY 0.680851 (-1475 3575);
PAINT MONO (-1475 3575);
DISPLAY INVISIBLE (-1475 3575);
FORCEPROP 2 LAST SEC_TYPE 0402
R 1
J 0
(-1475 3575);
DISPLAY 1.021277 (-1475 3575);
PAINT ORANGE (-1475 3575);
DISPLAY INVISIBLE (-1475 3575);
FORCEPROP 2 LAST CDS_LIB mstr_discrete
R 1
J 0
(-1250 3525);
PAINT ORANGE (-1250 3525);
DISPLAY INVISIBLE (-1250 3525);
FORCEPROP 2 LAST BOM_COST SB
J 0
(-1200 3700);
PAINT ORANGE (-1200 3700);
DISPLAY INVISIBLE (-1200 3700);
FORCEPROP 2 LAST ROOM SB
R 1
J 0
(-1325 3570);
DISPLAY 1.361702 (-1325 3570);
PAINT ORANGE (-1325 3570);
DISPLAY INVISIBLE (-1325 3570);
FORCEADD TTL1G126_A..1
R 6
(-1550 2600);
FORCEPROP 1 LAST PART_NUMBER A79322-001
J 0
(-1450 2661);
DISPLAY 0.617021 (-1450 2661);
PAINT BLUE (-1450 2661);
FORCEPROP 1 LAST LOCATION U6W6
J 0
(-1775 2671);
DISPLAY 0.617021 (-1775 2671);
PAINT AQUA (-1775 2671);
FORCEPROP 1 LASTPIN (-1700 2600) $PN 2
J 2
(-1675 2561);
DISPLAY 0.617021 (-1675 2561);
PAINT WHITE (-1675 2561);
FORCEPROP 1 LASTPIN (-1550 2700) $PN 1
J 0
(-1545 2721);
DISPLAY 0.617021 (-1545 2721);
PAINT WHITE (-1545 2721);
FORCEPROP 1 LASTPIN (-1400 2600) $PN 4
J 0
(-1435 2561);
DISPLAY 0.617021 (-1435 2561);
PAINT WHITE (-1435 2561);
FORCEPROP 1 LAST MATERIAL IC
J 0
(-1300 2496);
DISPLAY 0.617021 (-1300 2496);
PAINT SKYBLUE (-1300 2496);
FORCEPROP 1 LAST VALUE 74HC1G126
J 0
(-1525 2496);
DISPLAY 0.617021 (-1525 2496);
PAINT SKYBLUE (-1525 2496);
FORCEPROP 1 LAST POWER_GROUP VCC=P3V3_STBY;GND=GND;
J 0
(-1450 2711);
DISPLAY 0.617021 (-1450 2711);
PAINT ORANGE (-1450 2711);
FORCEPROP 2 LAST CDS_LOCATION U6W6
J 0
(-1600 2371);
DISPLAY 0.617021 (-1600 2371);
PAINT AQUA (-1600 2371);
DISPLAY INVISIBLE (-1600 2371);
FORCEPROP 1 LAST PACK_TYPE SOT
J 0
(-1600 2304);
DISPLAY 0.978723 (-1600 2304);
PAINT SKYBLUE (-1600 2304);
DISPLAY INVISIBLE (-1600 2304);
FORCEPROP 2 LAST ROOM SB
J 0
(-1600 2302);
DISPLAY 1.021277 (-1600 2302);
PAINT ORANGE (-1600 2302);
DISPLAY INVISIBLE (-1600 2302);
FORCEPROP 2 LAST SEC 1
J 0
(-1600 2318);
DISPLAY 0.680851 (-1600 2318);
PAINT MONO (-1600 2318);
DISPLAY INVISIBLE (-1600 2318);
FORCEPROP 2 LAST CDS_LIB mstr_ttl
J 0
(-1550 2553);
PAINT MONO (-1550 2553);
DISPLAY INVISIBLE (-1550 2553);
FORCEPROP 2 LAST SEC_TYPE SOT
J 0
(-1600 2302);
DISPLAY 1.021277 (-1600 2302);
PAINT ORANGE (-1600 2302);
DISPLAY INVISIBLE (-1600 2302);
FORCEPROP 2 LAST BOM_COST SB
J 0
(-1600 2252);
DISPLAY 1.021277 (-1600 2252);
PAINT ORANGE (-1600 2252);
DISPLAY INVISIBLE (-1600 2252);
FORCEPROP 1 LAST PATH I157
J 2
(-1655 2500);
DISPLAY 0.978723 (-1655 2500);
PAINT GREEN (-1655 2500);
DISPLAY INVISIBLE (-1655 2500);
FORCEADD RES..2
R 1
(-1300 2950);
FORCEPROP 1 LAST VALUE 10.0K
J 0
(-1500 2895);
DISPLAY 0.617021 (-1500 2895);
PAINT SKYBLUE (-1500 2895);
FORCEPROP 1 LAST LOCATION R6W39
J 0
(-1500 2995);
DISPLAY 0.617021 (-1500 2995);
PAINT AQUA (-1500 2995);
FORCEPROP 1 LAST TOLERANCE 1%
J 0
(-1500 2845);
DISPLAY 0.617021 (-1500 2845);
PAINT SKYBLUE (-1500 2845);
FORCEPROP 1 LAST MATERIAL CHIP
J 0
(-1350 2840);
DISPLAY 0.617021 (-1350 2840);
PAINT SKYBLUE (-1350 2840);
FORCEPROP 1 LAST WATTAGE 1/16W
J 0
(-1350 2890);
DISPLAY 0.617021 (-1350 2890);
PAINT SKYBLUE (-1350 2890);
FORCEPROP 1 LASTPIN (-1200 2950) $PN 2
J 0
(-1210 2955);
DISPLAY 0.617021 (-1210 2955);
PAINT ORANGE (-1210 2955);
FORCEPROP 1 LASTPIN (-1400 2950) $PN 1
J 0
(-1412 2955);
DISPLAY 0.617021 (-1412 2955);
PAINT ORANGE (-1412 2955);
FORCEPROP 1 LAST PACK_TYPE 0402
J 0
(-1200 2840);
DISPLAY 0.617021 (-1200 2840);
PAINT SKYBLUE (-1200 2840);
FORCEPROP 1 LAST PART_NUMBER G21796-016
J 0
(-1200 2890);
DISPLAY 0.617021 (-1200 2890);
PAINT BLUE (-1200 2890);
FORCEPROP 1 LAST PATH I158
R 1
J 0
(-1475 3000);
DISPLAY 0.978723 (-1475 3000);
PAINT WHITE (-1475 3000);
DISPLAY INVISIBLE (-1475 3000);
FORCEPROP 0 LAST BOM_COST MIO_USB
R 1
J 0
(-1525 3000);
DISPLAY 1.021277 (-1525 3000);
PAINT ORANGE (-1525 3000);
DISPLAY INVISIBLE (-1525 3000);
FORCEPROP 2 LAST SEC_TYPE 0402
R 1
J 0
(-1525 3000);
DISPLAY 1.021277 (-1525 3000);
PAINT ORANGE (-1525 3000);
DISPLAY INVISIBLE (-1525 3000);
FORCEPROP 2 LAST SEC 1
R 1
J 0
(-1525 3000);
DISPLAY 0.680851 (-1525 3000);
PAINT MONO (-1525 3000);
DISPLAY INVISIBLE (-1525 3000);
FORCEPROP 2 LAST ROOM USB_REAR
R 1
J 0
(-1300 2950);
PAINT MONO (-1300 2950);
DISPLAY INVISIBLE (-1300 2950);
FORCEPROP 2 LAST CDS_LIB mstr_discrete
R 1
J 0
(-1300 2950);
PAINT MONO (-1300 2950);
DISPLAY INVISIBLE (-1300 2950);
FORCEADD P3V3_STBY..1
(-650 2950);
FORCEPROP 3 LASTPIN (-650 2900) SIG_NAME P3V3_STBY\g
J 0
(-640 2910);
DISPLAY 0.659574 (-640 2910);
PAINT MONO (-640 2910);
DISPLAY INVISIBLE (-640 2910);
FORCEPROP 1 LAST PATH I159
J 0
(-605 2952);
DISPLAY 0.340426 (-605 2952);
PAINT GREEN (-605 2952);
DISPLAY INVISIBLE (-605 2952);
FORCEPROP 1 LAST SIZE 1B
J 0
(-605 2972);
DISPLAY 0.340426 (-605 2972);
PAINT GREEN (-605 2972);
DISPLAY INVISIBLE (-605 2972);
FORCEPROP 2 LAST CDS_LIB mstr_symbols
J 0
(-650 2950);
PAINT MONO (-650 2950);
DISPLAY INVISIBLE (-650 2950);
FORCEPROP 1 LAST VOLTAGE 3.3V
J 0
(-695 2907);
DISPLAY 0.340426 (-695 2907);
PAINT GREEN (-695 2907);
DISPLAY INVISIBLE (-695 2907);
FORCEPROP 1 LAST BODY_TYPE PLUMBING
J 0
(-695 2907);
DISPLAY 0.340426 (-695 2907);
PAINT GREEN (-695 2907);
DISPLAY INVISIBLE (-695 2907);
FORCEPROP 1 LAST HDL_POWER P3V3_STBY
J 0
(-950 2825);
DISPLAY 0.872340 (-950 2825);
PAINT ORANGE (-950 2825);
DISPLAY INVISIBLE (-950 2825);
FORCEADD RES..1
(-5650 4600);
FORCEPROP 1 LASTPIN (-5550 4600) $PN 2
J 0
(-5588 4612);
DISPLAY 0.617021 (-5588 4612);
PAINT WHITE (-5588 4612);
FORCEPROP 1 LAST WATTAGE 1/16W
J 0
(-5350 4650);
DISPLAY 0.510638 (-5350 4650);
PAINT SKYBLUE (-5350 4650);
FORCEPROP 0 LAST POP NOPOP
J 0
(-5900 4450);
DISPLAY 1.021277 (-5900 4450);
PAINT RED (-5900 4450);
FORCEPROP 1 LAST LOCATION R1M5
J 0
(-5850 4650);
DISPLAY 0.617021 (-5850 4650);
PAINT AQUA (-5850 4650);
FORCEPROP 1 LAST MATERIAL CHIP
J 0
(-5875 4550);
DISPLAY 0.617021 (-5875 4550);
PAINT SKYBLUE (-5875 4550);
FORCEPROP 1 LAST PACK_TYPE 0402
J 0
(-5550 4550);
DISPLAY 0.617021 (-5550 4550);
PAINT SKYBLUE (-5550 4550);
FORCEPROP 1 LAST TOLERANCE 5%
J 0
(-5725 4550);
DISPLAY 0.617021 (-5725 4550);
PAINT SKYBLUE (-5725 4550);
FORCEPROP 1 LASTPIN (-5750 4600) $PN 1
J 0
(-5738 4612);
DISPLAY 0.617021 (-5738 4612);
PAINT WHITE (-5738 4612);
FORCEPROP 1 LAST VALUE 0.0
J 2
(-5625 4650);
DISPLAY 0.617021 (-5625 4650);
PAINT SKYBLUE (-5625 4650);
FORCEPROP 1 LAST PART_NUMBER G21497-005
J 0
(-5575 4650);
DISPLAY 0.510638 (-5575 4650);
PAINT BLUE (-5575 4650);
FORCEPROP 2 LAST CDS_LOCATION R1M5
J 0
(-5700 4650);
DISPLAY 0.617021 (-5700 4650);
PAINT AQUA (-5700 4650);
DISPLAY INVISIBLE (-5700 4650);
FORCEPROP 1 LAST PATH I16
J 0
(-5700 4750);
DISPLAY 0.978723 (-5700 4750);
PAINT WHITE (-5700 4750);
DISPLAY INVISIBLE (-5700 4750);
FORCEPROP 2 LAST CDS_LIB mstr_discrete
J 0
(-5650 4600);
PAINT MONO (-5650 4600);
DISPLAY INVISIBLE (-5650 4600);
FORCEPROP 2 LAST SEC_TYPE 0402
J 0
(-5700 4800);
DISPLAY 1.021277 (-5700 4800);
PAINT ORANGE (-5700 4800);
DISPLAY INVISIBLE (-5700 4800);
FORCEPROP 2 LAST SEC 1
J 0
(-5700 4800);
DISPLAY 0.680851 (-5700 4800);
PAINT MONO (-5700 4800);
DISPLAY INVISIBLE (-5700 4800);
FORCEPROP 0 LAST BOM_COST MIO_USB
J 0
(-5475 4750);
DISPLAY 1.021277 (-5475 4750);
PAINT ORANGE (-5475 4750);
DISPLAY INVISIBLE (-5475 4750);
FORCEPROP 0 LAST ROOM USB_REAR
J 0
(-5475 4700);
DISPLAY 1.021277 (-5475 4700);
PAINT ORANGE (-5475 4700);
DISPLAY INVISIBLE (-5475 4700);
FORCEADD RES..1
(-700 3150);
FORCEPROP 1 LAST TOLERANCE 1%
J 0
(-900 3050);
DISPLAY 0.617021 (-900 3050);
PAINT SKYBLUE (-900 3050);
FORCEPROP 1 LAST VALUE 10.0
J 0
(-900 3100);
DISPLAY 0.617021 (-900 3100);
PAINT SKYBLUE (-900 3100);
FORCEPROP 1 LASTPIN (-800 3150) $PN 1
J 0
(-788 3162);
DISPLAY 0.617021 (-788 3162);
PAINT MONO (-788 3162);
FORCEPROP 1 LAST MATERIAL CHIP
J 0
(-750 3050);
DISPLAY 0.617021 (-750 3050);
PAINT SKYBLUE (-750 3050);
FORCEPROP 1 LAST WATTAGE 1/16W
J 0
(-750 3100);
DISPLAY 0.617021 (-750 3100);
PAINT SKYBLUE (-750 3100);
FORCEPROP 1 LAST PART_NUMBER G21796-066
J 0
(-600 3100);
DISPLAY 0.617021 (-600 3100);
PAINT BLUE (-600 3100);
FORCEPROP 1 LASTPIN (-600 3150) $PN 2
J 0
(-638 3162);
DISPLAY 0.617021 (-638 3162);
PAINT MONO (-638 3162);
FORCEPROP 1 LAST LOCATION R6W37
J 0
(-900 3200);
DISPLAY 0.617021 (-900 3200);
PAINT AQUA (-900 3200);
FORCEPROP 1 LAST PACK_TYPE 0402
J 0
(-600 3050);
DISPLAY 0.617021 (-600 3050);
PAINT SKYBLUE (-600 3050);
FORCEPROP 2 LAST CDS_LOCATION R6W37
J 0
(-750 3200);
DISPLAY 0.617021 (-750 3200);
PAINT AQUA (-750 3200);
DISPLAY INVISIBLE (-750 3200);
FORCEPROP 2 LAST CDS_LIB mstr_discrete
J 0
(-700 3150);
PAINT MONO (-700 3150);
DISPLAY INVISIBLE (-700 3150);
FORCEPROP 2 LAST BOM_COST SM_CONTROLLER
J 0
(-750 3250);
PAINT MONO (-750 3250);
DISPLAY INVISIBLE (-750 3250);
FORCEPROP 2 LAST CDS_SEC 1
J 0
(-750 3350);
DISPLAY 1.404255 (-750 3350);
PAINT ORANGE (-750 3350);
DISPLAY INVISIBLE (-750 3350);
FORCEPROP 2 LAST $SEC 1
J 0
(-750 3350);
DISPLAY 0.936170 (-750 3350);
PAINT MONO (-750 3350);
DISPLAY INVISIBLE (-750 3350);
FORCEPROP 2 LAST ROOM MEM
J 0
(-750 3250);
PAINT MONO (-750 3250);
DISPLAY INVISIBLE (-750 3250);
FORCEPROP 1 LAST PATH I160
J 0
(-750 3300);
DISPLAY 0.978723 (-750 3300);
PAINT WHITE (-750 3300);
DISPLAY INVISIBLE (-750 3300);
FORCEADD RES..1
(-725 2600);
FORCEPROP 1 LASTPIN (-825 2600) $PN 1
J 0
(-813 2612);
DISPLAY 0.617021 (-813 2612);
PAINT MONO (-813 2612);
FORCEPROP 1 LAST WATTAGE 1/16W
J 0
(-775 2550);
DISPLAY 0.617021 (-775 2550);
PAINT SKYBLUE (-775 2550);
FORCEPROP 1 LASTPIN (-625 2600) $PN 2
J 0
(-663 2612);
DISPLAY 0.617021 (-663 2612);
PAINT MONO (-663 2612);
FORCEPROP 1 LAST MATERIAL CHIP
J 0
(-775 2500);
DISPLAY 0.617021 (-775 2500);
PAINT SKYBLUE (-775 2500);
FORCEPROP 1 LAST PACK_TYPE 0402
J 0
(-625 2500);
DISPLAY 0.617021 (-625 2500);
PAINT SKYBLUE (-625 2500);
FORCEPROP 1 LAST LOCATION R6W36
J 0
(-925 2650);
DISPLAY 0.617021 (-925 2650);
PAINT AQUA (-925 2650);
FORCEPROP 1 LAST TOLERANCE 1%
J 0
(-925 2500);
DISPLAY 0.617021 (-925 2500);
PAINT SKYBLUE (-925 2500);
FORCEPROP 1 LAST PART_NUMBER G21796-066
J 0
(-625 2550);
DISPLAY 0.617021 (-625 2550);
PAINT BLUE (-625 2550);
FORCEPROP 1 LAST VALUE 10.0
J 0
(-925 2550);
DISPLAY 0.617021 (-925 2550);
PAINT SKYBLUE (-925 2550);
FORCEPROP 2 LAST CDS_LOCATION R6W36
J 0
(-775 2650);
DISPLAY 0.617021 (-775 2650);
PAINT AQUA (-775 2650);
DISPLAY INVISIBLE (-775 2650);
FORCEPROP 1 LAST PATH I161
J 0
(-775 2750);
DISPLAY 0.978723 (-775 2750);
PAINT WHITE (-775 2750);
DISPLAY INVISIBLE (-775 2750);
FORCEPROP 2 LAST ROOM MEM
J 0
(-775 2700);
PAINT MONO (-775 2700);
DISPLAY INVISIBLE (-775 2700);
FORCEPROP 2 LAST $SEC 1
J 0
(-775 2800);
DISPLAY 0.936170 (-775 2800);
PAINT MONO (-775 2800);
DISPLAY INVISIBLE (-775 2800);
FORCEPROP 2 LAST CDS_SEC 1
J 0
(-775 2800);
DISPLAY 1.404255 (-775 2800);
PAINT ORANGE (-775 2800);
DISPLAY INVISIBLE (-775 2800);
FORCEPROP 2 LAST BOM_COST SM_CONTROLLER
J 0
(-775 2700);
PAINT MONO (-775 2700);
DISPLAY INVISIBLE (-775 2700);
FORCEPROP 2 LAST CDS_LIB mstr_discrete
J 0
(-725 2600);
PAINT MONO (-725 2600);
DISPLAY INVISIBLE (-725 2600);
FORCEADD PCA9617..1
(-4900 2000);
FORCEPROP 2 LASTPIN (-4500 2050) $PN 7
J 0
(-4490 2060);
DISPLAY 0.617021 (-4490 2060);
PAINT MONO (-4490 2060);
FORCEPROP 2 LASTPIN (-5300 2000) $PN 3
J 2
(-5310 2010);
DISPLAY 0.617021 (-5310 2010);
PAINT MONO (-5310 2010);
FORCEPROP 2 LASTPIN (-5300 1900) $PN 5
J 2
(-5310 1910);
DISPLAY 0.617021 (-5310 1910);
PAINT MONO (-5310 1910);
FORCEPROP 2 LASTPIN (-4500 2150) $PN 8
J 0
(-4490 2160);
DISPLAY 0.617021 (-4490 2160);
PAINT MONO (-4490 2160);
FORCEPROP 2 LASTPIN (-5300 2050) $PN 2
J 2
(-5310 2060);
DISPLAY 0.617021 (-5310 2060);
PAINT MONO (-5310 2060);
FORCEPROP 1 LAST MATERIAL IC
J 0
(-5250 2275);
DISPLAY 0.617021 (-5250 2275);
PAINT SKYBLUE (-5250 2275);
FORCEPROP 1 LAST LOCATION U1W3
J 0
(-5250 2325);
DISPLAY 0.617021 (-5250 2325);
PAINT AQUA (-5250 2325);
FORCEPROP 2 LASTPIN (-5300 2150) $PN 1
J 2
(-5310 2160);
DISPLAY 0.617021 (-5310 2160);
PAINT MONO (-5310 2160);
FORCEPROP 2 LASTPIN (-4500 2000) $PN 6
J 0
(-4490 2010);
DISPLAY 0.617021 (-4490 2010);
PAINT MONO (-4490 2010);
FORCEPROP 1 LAST PART_NUMBER G81764-001
J 0
(-5250 1800);
DISPLAY 0.617021 (-5250 1800);
PAINT BLUE (-5250 1800);
FORCEPROP 1 LAST POWER_GROUP GND=GND
J 0
(-5250 1750);
DISPLAY 0.617021 (-5250 1750);
PAINT ORANGE (-5250 1750);
FORCEPROP 2 LAST CDS_LOCATION U1W3
J 0
(-5250 2325);
DISPLAY 0.617021 (-5250 2325);
PAINT AQUA (-5250 2325);
DISPLAY INVISIBLE (-5250 2325);
FORCEPROP 1 LAST PACK_TYPE SSOP
J 0
(-5250 2375);
PAINT SKYBLUE (-5250 2375);
DISPLAY INVISIBLE (-5250 2375);
FORCEPROP 2 LAST CDS_LIB mstr_digital
J 0
(-4900 2000);
PAINT MONO (-4900 2000);
DISPLAY INVISIBLE (-4900 2000);
FORCEPROP 2 LAST BOM_COST SM_CONTROLLER
J 0
(-5250 2375);
PAINT MONO (-5250 2375);
DISPLAY INVISIBLE (-5250 2375);
FORCEPROP 2 LAST CDS_SEC 1
J 0
(-5250 2375);
DISPLAY 1.404255 (-5250 2375);
PAINT ORANGE (-5250 2375);
DISPLAY INVISIBLE (-5250 2375);
FORCEPROP 2 LAST $SEC 1
J 0
(-5250 2375);
DISPLAY 0.936170 (-5250 2375);
PAINT MONO (-5250 2375);
DISPLAY INVISIBLE (-5250 2375);
FORCEPROP 2 LAST ROOM MEM
J 0
(-5250 2375);
PAINT MONO (-5250 2375);
DISPLAY INVISIBLE (-5250 2375);
FORCEPROP 1 LAST PATH I162
J 0
(-4775 2275);
PAINT GREEN (-4775 2275);
DISPLAY INVISIBLE (-4775 2275);
FORCEADD CAP_A..1
(-4175 1650);
FORCEPROP 1 LASTPIN (-4175 1750) $PN 1
J 0
(-4165 1730);
DISPLAY 0.617021 (-4165 1730);
PAINT MONO (-4165 1730);
FORCEPROP 1 LAST LOCATION C1W18
J 0
(-4125 1750);
DISPLAY 0.617021 (-4125 1750);
PAINT AQUA (-4125 1750);
FORCEPROP 1 LAST PART_NUMBER A36096-030
J 0
(-4125 1500);
DISPLAY 0.617021 (-4125 1500);
PAINT BLUE (-4125 1500);
FORCEPROP 1 LASTPIN (-4175 1550) $PN 2
J 0
(-4165 1530);
DISPLAY 0.617021 (-4165 1530);
PAINT MONO (-4165 1530);
FORCEPROP 1 LAST VOLTAGE 16V
J 0
(-4125 1650);
DISPLAY 0.617021 (-4125 1650);
PAINT SKYBLUE (-4125 1650);
FORCEPROP 1 LAST MATERIAL X7R
J 0
(-4125 1550);
DISPLAY 0.617021 (-4125 1550);
PAINT SKYBLUE (-4125 1550);
FORCEPROP 1 LAST VALUE 0.1UF
J 0
(-4125 1700);
DISPLAY 0.617021 (-4125 1700);
PAINT SKYBLUE (-4125 1700);
FORCEPROP 1 LAST PACK_TYPE 0402V
J 0
(-4125 1450);
DISPLAY 0.617021 (-4125 1450);
PAINT SKYBLUE (-4125 1450);
FORCEPROP 1 LAST TOLERANCE 10%
J 0
(-4125 1600);
DISPLAY 0.617021 (-4125 1600);
PAINT SKYBLUE (-4125 1600);
FORCEPROP 2 LAST CDS_LOCATION C1W18
J 0
(-4125 1750);
DISPLAY 0.617021 (-4125 1750);
PAINT AQUA (-4125 1750);
DISPLAY INVISIBLE (-4125 1750);
FORCEPROP 1 LAST PATH I163
J 0
(-4125 1800);
DISPLAY 0.978723 (-4125 1800);
PAINT WHITE (-4125 1800);
DISPLAY INVISIBLE (-4125 1800);
FORCEPROP 2 LAST $SEC 1
J 0
(-4125 1850);
DISPLAY 0.936170 (-4125 1850);
PAINT MONO (-4125 1850);
DISPLAY INVISIBLE (-4125 1850);
FORCEPROP 2 LAST CDS_SEC 1
J 0
(-4125 1850);
DISPLAY 1.404255 (-4125 1850);
PAINT ORANGE (-4125 1850);
DISPLAY INVISIBLE (-4125 1850);
FORCEPROP 2 LAST CDS_LIB dev_discrete
J 0
(-4175 1650);
PAINT ORANGE (-4175 1650);
DISPLAY INVISIBLE (-4175 1650);
FORCEPROP 2 LAST SIGNAL_MODEL DEFAULT_CAPACITOR_100000pF_2_1
J 0
(-4125 1875);
DISPLAY 1.617021 (-4125 1875);
PAINT MONO (-4125 1875);
DISPLAY INVISIBLE (-4125 1875);
FORCEPROP 2 LAST CD_SEC 1
J 0
(-4125 1875);
DISPLAY 1.617021 (-4125 1875);
PAINT MONO (-4125 1875);
DISPLAY INVISIBLE (-4125 1875);
FORCEPROP 2 LAST BOM_COST SM_CONTROLLER
J 0
(-4125 1800);
DISPLAY 2.170213 (-4125 1800);
PAINT ORANGE (-4125 1800);
DISPLAY INVISIBLE (-4125 1800);
FORCEPROP 2 LAST ROOM MEM
J 0
(-4125 1775);
PAINT MONO (-4125 1775);
DISPLAY INVISIBLE (-4125 1775);
FORCEADD GND..1
(-4175 1450);
FORCEPROP 3 LASTPIN (-4175 1500) SIG_NAME GND\g
J 0
(-4165 1510);
DISPLAY 0.659574 (-4165 1510);
PAINT MONO (-4165 1510);
DISPLAY INVISIBLE (-4165 1510);
FORCEPROP 1 LAST HDL_POWER GND
J 0
(-4175 1600);
DISPLAY 2.361702 (-4175 1600);
PAINT GREEN (-4175 1600);
DISPLAY INVISIBLE (-4175 1600);
FORCEPROP 1 LAST BODY_TYPE PLUMBING
J 0
(-4220 1407);
DISPLAY 0.340426 (-4220 1407);
PAINT GREEN (-4220 1407);
DISPLAY INVISIBLE (-4220 1407);
FORCEPROP 1 LAST VOLTAGE 0
J 0
(-4175 1450);
PAINT SKYBLUE (-4175 1450);
DISPLAY INVISIBLE (-4175 1450);
FORCEPROP 2 LAST CDS_LIB mstr_symbols
J 0
(-4175 1450);
PAINT MONO (-4175 1450);
DISPLAY INVISIBLE (-4175 1450);
FORCEPROP 1 LAST SIZE 1B
J 0
(-4100 1400);
DISPLAY 2.361702 (-4100 1400);
PAINT GREEN (-4100 1400);
DISPLAY INVISIBLE (-4100 1400);
FORCEPROP 2 LAST BOM_COST SM_CONTROLLER
J 0
(-4575 1525);
DISPLAY 1.617021 (-4575 1525);
PAINT ORANGE (-4575 1525);
DISPLAY INVISIBLE (-4575 1525);
FORCEPROP 2 LAST ROOM SMB
J 0
(-4275 1525);
PAINT MONO (-4275 1525);
DISPLAY INVISIBLE (-4275 1525);
FORCEPROP 1 LAST PATH I164
J 0
(-4100 1450);
DISPLAY 0.872340 (-4100 1450);
PAINT AQUA (-4100 1450);
DISPLAY INVISIBLE (-4100 1450);
FORCEADD CAP_A..1
(-3775 1650);
FORCEPROP 1 LASTPIN (-3775 1550) $PN 2
J 0
(-3765 1530);
DISPLAY 0.617021 (-3765 1530);
PAINT MONO (-3765 1530);
FORCEPROP 1 LAST PACK_TYPE 0402V
J 0
(-3725 1450);
DISPLAY 0.617021 (-3725 1450);
PAINT SKYBLUE (-3725 1450);
FORCEPROP 1 LAST TOLERANCE 10%
J 0
(-3725 1600);
DISPLAY 0.617021 (-3725 1600);
PAINT SKYBLUE (-3725 1600);
FORCEPROP 1 LASTPIN (-3775 1750) $PN 1
J 0
(-3765 1730);
DISPLAY 0.617021 (-3765 1730);
PAINT MONO (-3765 1730);
FORCEPROP 1 LAST VALUE 0.1UF
J 0
(-3725 1700);
DISPLAY 0.617021 (-3725 1700);
PAINT SKYBLUE (-3725 1700);
FORCEPROP 1 LAST MATERIAL X7R
J 0
(-3725 1550);
DISPLAY 0.617021 (-3725 1550);
PAINT SKYBLUE (-3725 1550);
FORCEPROP 1 LAST LOCATION C1W19
J 0
(-3725 1750);
DISPLAY 0.617021 (-3725 1750);
PAINT AQUA (-3725 1750);
FORCEPROP 1 LAST PART_NUMBER A36096-030
J 0
(-3725 1500);
DISPLAY 0.617021 (-3725 1500);
PAINT BLUE (-3725 1500);
FORCEPROP 1 LAST VOLTAGE 16V
J 0
(-3725 1650);
DISPLAY 0.617021 (-3725 1650);
PAINT SKYBLUE (-3725 1650);
FORCEPROP 2 LAST CDS_LOCATION C1W19
J 0
(-3725 1750);
DISPLAY 0.617021 (-3725 1750);
PAINT AQUA (-3725 1750);
DISPLAY INVISIBLE (-3725 1750);
FORCEPROP 2 LAST ROOM MEM
J 0
(-3725 1775);
PAINT MONO (-3725 1775);
DISPLAY INVISIBLE (-3725 1775);
FORCEPROP 2 LAST CD_SEC 1
J 0
(-3725 1875);
DISPLAY 1.617021 (-3725 1875);
PAINT MONO (-3725 1875);
DISPLAY INVISIBLE (-3725 1875);
FORCEPROP 2 LAST SIGNAL_MODEL DEFAULT_CAPACITOR_100000pF_2_1
J 0
(-3725 1875);
DISPLAY 1.617021 (-3725 1875);
PAINT MONO (-3725 1875);
DISPLAY INVISIBLE (-3725 1875);
FORCEPROP 2 LAST BOM_COST SM_CONTROLLER
J 0
(-3725 1800);
DISPLAY 2.170213 (-3725 1800);
PAINT ORANGE (-3725 1800);
DISPLAY INVISIBLE (-3725 1800);
FORCEPROP 2 LAST CDS_LIB dev_discrete
J 0
(-3775 1650);
PAINT ORANGE (-3775 1650);
DISPLAY INVISIBLE (-3775 1650);
FORCEPROP 2 LAST CDS_SEC 1
J 0
(-3725 1850);
DISPLAY 1.404255 (-3725 1850);
PAINT ORANGE (-3725 1850);
DISPLAY INVISIBLE (-3725 1850);
FORCEPROP 2 LAST $SEC 1
J 0
(-3725 1850);
DISPLAY 0.936170 (-3725 1850);
PAINT MONO (-3725 1850);
DISPLAY INVISIBLE (-3725 1850);
FORCEPROP 1 LAST PATH I166
J 0
(-3725 1800);
DISPLAY 0.978723 (-3725 1800);
PAINT WHITE (-3725 1800);
DISPLAY INVISIBLE (-3725 1800);
FORCEADD GND..1
(-3775 1450);
FORCEPROP 3 LASTPIN (-3775 1500) SIG_NAME GND\g
J 0
(-3765 1510);
DISPLAY 0.659574 (-3765 1510);
PAINT MONO (-3765 1510);
DISPLAY INVISIBLE (-3765 1510);
FORCEPROP 1 LAST PATH I167
J 0
(-3700 1450);
DISPLAY 0.872340 (-3700 1450);
PAINT AQUA (-3700 1450);
DISPLAY INVISIBLE (-3700 1450);
FORCEPROP 2 LAST ROOM SMB
J 0
(-3875 1525);
PAINT MONO (-3875 1525);
DISPLAY INVISIBLE (-3875 1525);
FORCEPROP 1 LAST SIZE 1B
J 0
(-3700 1400);
DISPLAY 2.361702 (-3700 1400);
PAINT GREEN (-3700 1400);
DISPLAY INVISIBLE (-3700 1400);
FORCEPROP 2 LAST CDS_LIB mstr_symbols
J 0
(-3775 1450);
PAINT MONO (-3775 1450);
DISPLAY INVISIBLE (-3775 1450);
FORCEPROP 2 LAST BOM_COST SM_CONTROLLER
J 0
(-4175 1525);
DISPLAY 1.617021 (-4175 1525);
PAINT ORANGE (-4175 1525);
DISPLAY INVISIBLE (-4175 1525);
FORCEPROP 1 LAST VOLTAGE 0
J 0
(-3775 1450);
PAINT SKYBLUE (-3775 1450);
DISPLAY INVISIBLE (-3775 1450);
FORCEPROP 1 LAST BODY_TYPE PLUMBING
J 0
(-3820 1407);
DISPLAY 0.340426 (-3820 1407);
PAINT GREEN (-3820 1407);
DISPLAY INVISIBLE (-3820 1407);
FORCEPROP 1 LAST HDL_POWER GND
J 0
(-3775 1600);
DISPLAY 2.361702 (-3775 1600);
PAINT GREEN (-3775 1600);
DISPLAY INVISIBLE (-3775 1600);
FORCEADD P3V3_STBY..1
(-4175 1850);
FORCEPROP 3 LASTPIN (-4175 1800) SIG_NAME P3V3_STBY\g
J 0
(-4165 1810);
DISPLAY 0.659574 (-4165 1810);
PAINT MONO (-4165 1810);
DISPLAY INVISIBLE (-4165 1810);
FORCEPROP 1 LAST PATH I168
J 0
(-4130 1852);
DISPLAY 0.340426 (-4130 1852);
PAINT GREEN (-4130 1852);
DISPLAY INVISIBLE (-4130 1852);
FORCEPROP 1 LAST HDL_POWER P3V3_STBY
J 0
(-4475 1725);
DISPLAY 0.872340 (-4475 1725);
PAINT ORANGE (-4475 1725);
DISPLAY INVISIBLE (-4475 1725);
FORCEPROP 1 LAST BODY_TYPE PLUMBING
J 0
(-4220 1807);
DISPLAY 0.340426 (-4220 1807);
PAINT GREEN (-4220 1807);
DISPLAY INVISIBLE (-4220 1807);
FORCEPROP 1 LAST VOLTAGE 3.3V
J 0
(-4220 1807);
DISPLAY 0.340426 (-4220 1807);
PAINT SKYBLUE (-4220 1807);
DISPLAY INVISIBLE (-4220 1807);
FORCEPROP 1 LAST SIZE 1B
J 0
(-4130 1872);
DISPLAY 0.340426 (-4130 1872);
PAINT GREEN (-4130 1872);
DISPLAY INVISIBLE (-4130 1872);
FORCEPROP 2 LAST CDS_LIB mstr_symbols
J 0
(-4175 1850);
PAINT MONO (-4175 1850);
DISPLAY INVISIBLE (-4175 1850);
FORCEADD P3V3_STBY..1
(-3775 1850);
FORCEPROP 3 LASTPIN (-3775 1800) SIG_NAME P3V3_STBY\g
J 0
(-3765 1810);
DISPLAY 0.659574 (-3765 1810);
PAINT MONO (-3765 1810);
DISPLAY INVISIBLE (-3765 1810);
FORCEPROP 1 LAST PATH I169
J 0
(-3730 1852);
DISPLAY 0.340426 (-3730 1852);
PAINT GREEN (-3730 1852);
DISPLAY INVISIBLE (-3730 1852);
FORCEPROP 1 LAST HDL_POWER P3V3_STBY
J 0
(-4075 1725);
DISPLAY 0.872340 (-4075 1725);
PAINT ORANGE (-4075 1725);
DISPLAY INVISIBLE (-4075 1725);
FORCEPROP 1 LAST BODY_TYPE PLUMBING
J 0
(-3820 1807);
DISPLAY 0.340426 (-3820 1807);
PAINT GREEN (-3820 1807);
DISPLAY INVISIBLE (-3820 1807);
FORCEPROP 1 LAST VOLTAGE 3.3V
J 0
(-3820 1807);
DISPLAY 0.340426 (-3820 1807);
PAINT SKYBLUE (-3820 1807);
DISPLAY INVISIBLE (-3820 1807);
FORCEPROP 1 LAST SIZE 1B
J 0
(-3730 1872);
DISPLAY 0.340426 (-3730 1872);
PAINT GREEN (-3730 1872);
DISPLAY INVISIBLE (-3730 1872);
FORCEPROP 2 LAST CDS_LIB mstr_symbols
J 0
(-3775 1850);
PAINT MONO (-3775 1850);
DISPLAY INVISIBLE (-3775 1850);
FORCEADD P3V3_STBY..1
(-4400 2300);
FORCEPROP 3 LASTPIN (-4400 2250) SIG_NAME P3V3_STBY\g
J 0
(-4390 2260);
DISPLAY 0.659574 (-4390 2260);
PAINT MONO (-4390 2260);
DISPLAY INVISIBLE (-4390 2260);
FORCEPROP 1 LAST HDL_POWER P3V3_STBY
J 0
(-4700 2175);
DISPLAY 0.872340 (-4700 2175);
PAINT ORANGE (-4700 2175);
DISPLAY INVISIBLE (-4700 2175);
FORCEPROP 1 LAST BODY_TYPE PLUMBING
J 0
(-4445 2257);
DISPLAY 0.340426 (-4445 2257);
PAINT GREEN (-4445 2257);
DISPLAY INVISIBLE (-4445 2257);
FORCEPROP 1 LAST VOLTAGE 3.3V
J 0
(-4445 2257);
DISPLAY 0.340426 (-4445 2257);
PAINT SKYBLUE (-4445 2257);
DISPLAY INVISIBLE (-4445 2257);
FORCEPROP 1 LAST SIZE 1B
J 0
(-4355 2322);
DISPLAY 0.340426 (-4355 2322);
PAINT GREEN (-4355 2322);
DISPLAY INVISIBLE (-4355 2322);
FORCEPROP 2 LAST CDS_LIB mstr_symbols
J 0
(-4400 2300);
PAINT MONO (-4400 2300);
DISPLAY INVISIBLE (-4400 2300);
FORCEPROP 1 LAST PATH I170
J 0
(-4355 2302);
DISPLAY 0.340426 (-4355 2302);
PAINT GREEN (-4355 2302);
DISPLAY INVISIBLE (-4355 2302);
FORCEADD P3V3_STBY..1
(-5400 2300);
FORCEPROP 3 LASTPIN (-5400 2250) SIG_NAME P3V3_STBY\g
J 0
(-5390 2260);
DISPLAY 0.659574 (-5390 2260);
PAINT MONO (-5390 2260);
DISPLAY INVISIBLE (-5390 2260);
FORCEPROP 2 LAST CDS_LIB mstr_symbols
J 0
(-5400 2300);
PAINT MONO (-5400 2300);
DISPLAY INVISIBLE (-5400 2300);
FORCEPROP 1 LAST SIZE 1B
J 0
(-5355 2322);
DISPLAY 0.340426 (-5355 2322);
PAINT GREEN (-5355 2322);
DISPLAY INVISIBLE (-5355 2322);
FORCEPROP 1 LAST VOLTAGE 3.3V
J 0
(-5445 2257);
DISPLAY 0.340426 (-5445 2257);
PAINT SKYBLUE (-5445 2257);
DISPLAY INVISIBLE (-5445 2257);
FORCEPROP 1 LAST BODY_TYPE PLUMBING
J 0
(-5445 2257);
DISPLAY 0.340426 (-5445 2257);
PAINT GREEN (-5445 2257);
DISPLAY INVISIBLE (-5445 2257);
FORCEPROP 1 LAST HDL_POWER P3V3_STBY
J 0
(-5700 2175);
DISPLAY 0.872340 (-5700 2175);
PAINT ORANGE (-5700 2175);
DISPLAY INVISIBLE (-5700 2175);
FORCEPROP 1 LAST PATH I171
J 0
(-5355 2302);
DISPLAY 0.340426 (-5355 2302);
PAINT GREEN (-5355 2302);
DISPLAY INVISIBLE (-5355 2302);
FORCEADD RES..1
R 5
(-6100 2250);
FORCEPROP 1 LAST MATERIAL CHIP
J 0
(-6050 2075);
DISPLAY 0.638298 (-6050 2075);
PAINT SKYBLUE (-6050 2075);
FORCEPROP 1 LAST PART_NUMBER G21796-072
J 0
(-6050 2125);
DISPLAY 0.638298 (-6050 2125);
PAINT BLUE (-6050 2125);
FORCEPROP 1 LAST PACK_TYPE 0402
J 0
(-6050 2175);
DISPLAY 0.638298 (-6050 2175);
PAINT SKYBLUE (-6050 2175);
FORCEPROP 1 LAST WATTAGE 1/16W
J 0
(-6050 2225);
DISPLAY 0.638298 (-6050 2225);
PAINT SKYBLUE (-6050 2225);
FORCEPROP 1 LASTPIN (-6100 2150) $PN 2
J 0
(-6088 2163);
DISPLAY 0.787234 (-6088 2163);
PAINT ORANGE (-6088 2163);
FORCEPROP 1 LAST TOLERANCE 1%
J 0
(-6050 2275);
DISPLAY 0.638298 (-6050 2275);
PAINT SKYBLUE (-6050 2275);
FORCEPROP 1 LASTPIN (-6100 2350) $PN 1
J 0
(-6088 2313);
DISPLAY 0.787234 (-6088 2313);
PAINT ORANGE (-6088 2313);
FORCEPROP 1 LAST VALUE 4.75K
J 0
(-6050 2325);
DISPLAY 0.638298 (-6050 2325);
PAINT SKYBLUE (-6050 2325);
FORCEPROP 1 LAST LOCATION R1W36
J 0
(-6050 2375);
DISPLAY 0.638298 (-6050 2375);
PAINT SKYBLUE (-6050 2375);
FORCEPROP 2 LAST CDS_LIB mstr_discrete
R 2
J 0
(-6100 2250);
PAINT MONO (-6100 2250);
DISPLAY INVISIBLE (-6100 2250);
FORCEPROP 2 LAST SEC_TYPE 0402
R 2
J 0
(-6150 2075);
DISPLAY 1.021277 (-6150 2075);
PAINT ORANGE (-6150 2075);
DISPLAY INVISIBLE (-6150 2075);
FORCEPROP 0 LAST SEC 1
R 3
J 0
(-6150 2075);
DISPLAY 0.680851 (-6150 2075);
PAINT MONO (-6150 2075);
DISPLAY INVISIBLE (-6150 2075);
FORCEPROP 1 LAST PATH I172
R 3
J 0
(-5950 2300);
DISPLAY 0.978723 (-5950 2300);
PAINT WHITE (-5950 2300);
DISPLAY INVISIBLE (-5950 2300);
FORCEADD RES..1
R 5
(-5800 2250);
FORCEPROP 1 LAST WATTAGE 1/16W
J 0
(-5750 2225);
DISPLAY 0.638298 (-5750 2225);
PAINT SKYBLUE (-5750 2225);
FORCEPROP 1 LAST PACK_TYPE 0402
J 0
(-5750 2175);
DISPLAY 0.638298 (-5750 2175);
PAINT SKYBLUE (-5750 2175);
FORCEPROP 1 LAST PART_NUMBER G21796-072
J 0
(-5750 2125);
DISPLAY 0.638298 (-5750 2125);
PAINT BLUE (-5750 2125);
FORCEPROP 1 LAST MATERIAL CHIP
J 0
(-5750 2075);
DISPLAY 0.638298 (-5750 2075);
PAINT SKYBLUE (-5750 2075);
FORCEPROP 1 LAST VALUE 4.75K
J 0
(-5750 2325);
DISPLAY 0.638298 (-5750 2325);
PAINT SKYBLUE (-5750 2325);
FORCEPROP 1 LAST LOCATION R1W37
J 0
(-5750 2375);
DISPLAY 0.638298 (-5750 2375);
PAINT SKYBLUE (-5750 2375);
FORCEPROP 1 LASTPIN (-5800 2350) $PN 1
J 0
(-5788 2313);
DISPLAY 0.787234 (-5788 2313);
PAINT ORANGE (-5788 2313);
FORCEPROP 1 LAST TOLERANCE 1%
J 0
(-5750 2275);
DISPLAY 0.638298 (-5750 2275);
PAINT SKYBLUE (-5750 2275);
FORCEPROP 1 LASTPIN (-5800 2150) $PN 2
J 0
(-5788 2163);
DISPLAY 0.787234 (-5788 2163);
PAINT ORANGE (-5788 2163);
FORCEPROP 1 LAST PATH I173
R 3
J 0
(-5650 2300);
DISPLAY 0.978723 (-5650 2300);
PAINT WHITE (-5650 2300);
DISPLAY INVISIBLE (-5650 2300);
FORCEPROP 2 LAST CDS_LIB mstr_discrete
R 2
J 0
(-5800 2250);
PAINT MONO (-5800 2250);
DISPLAY INVISIBLE (-5800 2250);
FORCEPROP 2 LAST SEC_TYPE 0402
R 2
J 0
(-5850 2075);
DISPLAY 1.021277 (-5850 2075);
PAINT ORANGE (-5850 2075);
DISPLAY INVISIBLE (-5850 2075);
FORCEPROP 0 LAST SEC 1
R 3
J 0
(-5850 2075);
DISPLAY 0.680851 (-5850 2075);
PAINT MONO (-5850 2075);
DISPLAY INVISIBLE (-5850 2075);
FORCEADD P3V3_STBY..1
(-6100 2550);
FORCEPROP 3 LASTPIN (-6100 2500) SIG_NAME P3V3_STBY\g
J 0
(-6090 2510);
DISPLAY 0.659574 (-6090 2510);
PAINT MONO (-6090 2510);
DISPLAY INVISIBLE (-6090 2510);
FORCEPROP 1 LAST PATH I174
J 0
(-6055 2552);
DISPLAY 0.340426 (-6055 2552);
PAINT GREEN (-6055 2552);
DISPLAY INVISIBLE (-6055 2552);
FORCEPROP 1 LAST HDL_POWER P3V3_STBY
J 0
(-6400 2425);
DISPLAY 0.872340 (-6400 2425);
PAINT ORANGE (-6400 2425);
DISPLAY INVISIBLE (-6400 2425);
FORCEPROP 1 LAST BODY_TYPE PLUMBING
J 0
(-6145 2507);
DISPLAY 0.340426 (-6145 2507);
PAINT GREEN (-6145 2507);
DISPLAY INVISIBLE (-6145 2507);
FORCEPROP 1 LAST VOLTAGE 3.3V
J 0
(-6145 2507);
DISPLAY 0.340426 (-6145 2507);
PAINT SKYBLUE (-6145 2507);
DISPLAY INVISIBLE (-6145 2507);
FORCEPROP 1 LAST SIZE 1B
J 0
(-6055 2572);
DISPLAY 0.340426 (-6055 2572);
PAINT GREEN (-6055 2572);
DISPLAY INVISIBLE (-6055 2572);
FORCEPROP 2 LAST CDS_LIB mstr_symbols
J 0
(-6100 2550);
PAINT MONO (-6100 2550);
DISPLAY INVISIBLE (-6100 2550);
FORCEADD RES..1
(-5950 1550);
FORCEPROP 0 LAST POP NOPOP
J 0
(-5375 1500);
DISPLAY 0.638298 (-5375 1500);
PAINT RED (-5375 1500);
FORCEPROP 1 LAST LOCATION R1W39
J 0
(-6400 1500);
DISPLAY 0.617021 (-6400 1500);
PAINT AQUA (-6400 1500);
FORCEPROP 1 LASTPIN (-5850 1550) $PN 2
J 0
(-5888 1562);
DISPLAY 0.617021 (-5888 1562);
PAINT WHITE (-5888 1562);
FORCEPROP 1 LAST VALUE 0.0
J 0
(-5900 1500);
DISPLAY 0.617021 (-5900 1500);
PAINT SKYBLUE (-5900 1500);
FORCEPROP 1 LAST PART_NUMBER G21497-005
J 0
(-6225 1500);
DISPLAY 0.617021 (-6225 1500);
PAINT BLUE (-6225 1500);
FORCEPROP 1 LASTPIN (-6050 1550) $PN 1
J 0
(-6038 1562);
DISPLAY 0.617021 (-6038 1562);
PAINT WHITE (-6038 1562);
FORCEPROP 1 LAST PACK_TYPE 0402
J 0
(-5700 1500);
DISPLAY 0.617021 (-5700 1500);
PAINT SKYBLUE (-5700 1500);
FORCEPROP 1 LAST TOLERANCE 5%
J 0
(-5800 1500);
DISPLAY 0.617021 (-5800 1500);
PAINT SKYBLUE (-5800 1500);
FORCEPROP 1 LAST WATTAGE 1/16W
J 0
(-5550 1500);
DISPLAY 0.638298 (-5550 1500);
PAINT SKYBLUE (-5550 1500);
FORCEPROP 2 LAST CDS_LOCATION R1W39
J 0
(-6425 1550);
DISPLAY 0.617021 (-6425 1550);
PAINT AQUA (-6425 1550);
DISPLAY INVISIBLE (-6425 1550);
FORCEPROP 1 LAST PATH I175
J 0
(-6000 1700);
DISPLAY 0.978723 (-6000 1700);
PAINT WHITE (-6000 1700);
DISPLAY INVISIBLE (-6000 1700);
FORCEPROP 2 LAST CDS_LIB mstr_discrete
J 0
(-5950 1550);
DISPLAY 1.340426 (-5950 1550);
PAINT ORANGE (-5950 1550);
DISPLAY INVISIBLE (-5950 1550);
FORCEPROP 2 LAST BOM_COST PROC_SIDEBAND
J 0
(-5950 1550);
PAINT MONO (-5950 1550);
DISPLAY INVISIBLE (-5950 1550);
FORCEPROP 1 LAST MATERIAL CHIP
J 0
(-5800 1450);
DISPLAY 0.510638 (-5800 1450);
PAINT SKYBLUE (-5800 1450);
DISPLAY INVISIBLE (-5800 1450);
FORCEPROP 2 LAST ROOM CPU0
J 0
(-6000 1700);
PAINT PEACH (-6000 1700);
DISPLAY INVISIBLE (-6000 1700);
FORCEPROP 2 LAST SEC_TYPE 0402
J 0
(-6000 1775);
DISPLAY 1.021277 (-6000 1775);
PAINT ORANGE (-6000 1775);
DISPLAY INVISIBLE (-6000 1775);
FORCEPROP 2 LAST SEC 1
J 0
(-6000 1775);
DISPLAY 0.680851 (-6000 1775);
PAINT MONO (-6000 1775);
DISPLAY INVISIBLE (-6000 1775);
FORCEADD RES..1
(-5950 1600);
FORCEPROP 1 LASTPIN (-6050 1600) $PN 1
J 0
(-6038 1612);
DISPLAY 0.617021 (-6038 1612);
PAINT WHITE (-6038 1612);
FORCEPROP 1 LAST WATTAGE 1/16W
J 0
(-5550 1650);
DISPLAY 0.638298 (-5550 1650);
PAINT SKYBLUE (-5550 1650);
FORCEPROP 1 LAST TOLERANCE 5%
J 0
(-5800 1650);
DISPLAY 0.617021 (-5800 1650);
PAINT SKYBLUE (-5800 1650);
FORCEPROP 1 LAST VALUE 0.0
J 0
(-5900 1650);
DISPLAY 0.617021 (-5900 1650);
PAINT SKYBLUE (-5900 1650);
FORCEPROP 1 LASTPIN (-5850 1600) $PN 2
J 0
(-5888 1612);
DISPLAY 0.617021 (-5888 1612);
PAINT WHITE (-5888 1612);
FORCEPROP 1 LAST PACK_TYPE 0402
J 0
(-5700 1650);
DISPLAY 0.617021 (-5700 1650);
PAINT SKYBLUE (-5700 1650);
FORCEPROP 1 LAST LOCATION R1W38
J 0
(-6400 1650);
DISPLAY 0.617021 (-6400 1650);
PAINT AQUA (-6400 1650);
FORCEPROP 1 LAST PART_NUMBER G21497-005
J 0
(-6225 1650);
DISPLAY 0.617021 (-6225 1650);
PAINT BLUE (-6225 1650);
FORCEPROP 0 LAST POP NOPOP
J 0
(-5375 1650);
DISPLAY 0.638298 (-5375 1650);
PAINT RED (-5375 1650);
FORCEPROP 2 LAST CDS_LOCATION R1W38
J 0
(-6425 1600);
DISPLAY 0.617021 (-6425 1600);
PAINT AQUA (-6425 1600);
DISPLAY INVISIBLE (-6425 1600);
FORCEPROP 2 LAST CDS_LIB mstr_discrete
J 0
(-5950 1600);
DISPLAY 1.340426 (-5950 1600);
PAINT ORANGE (-5950 1600);
DISPLAY INVISIBLE (-5950 1600);
FORCEPROP 2 LAST BOM_COST PROC_SIDEBAND
J 0
(-5950 1600);
PAINT MONO (-5950 1600);
DISPLAY INVISIBLE (-5950 1600);
FORCEPROP 1 LAST MATERIAL CHIP
J 0
(-5800 1500);
DISPLAY 0.510638 (-5800 1500);
PAINT SKYBLUE (-5800 1500);
DISPLAY INVISIBLE (-5800 1500);
FORCEPROP 2 LAST ROOM CPU0
J 0
(-6000 1750);
PAINT PEACH (-6000 1750);
DISPLAY INVISIBLE (-6000 1750);
FORCEPROP 2 LAST SEC_TYPE 0402
J 0
(-6000 1825);
DISPLAY 1.021277 (-6000 1825);
PAINT ORANGE (-6000 1825);
DISPLAY INVISIBLE (-6000 1825);
FORCEPROP 2 LAST SEC 1
J 0
(-6000 1825);
DISPLAY 0.680851 (-6000 1825);
PAINT MONO (-6000 1825);
DISPLAY INVISIBLE (-6000 1825);
FORCEPROP 1 LAST PATH I176
J 0
(-6000 1750);
DISPLAY 0.978723 (-6000 1750);
PAINT WHITE (-6000 1750);
DISPLAY INVISIBLE (-6000 1750);
FORCEADD RES..1
R 5
(-2150 4950);
FORCEPROP 1 LAST VALUE 4.75K
J 0
(-2100 5025);
DISPLAY 0.638298 (-2100 5025);
PAINT SKYBLUE (-2100 5025);
FORCEPROP 1 LASTPIN (-2150 5050) $PN 1
J 0
(-2138 5013);
DISPLAY 0.787234 (-2138 5013);
PAINT ORANGE (-2138 5013);
FORCEPROP 1 LASTPIN (-2150 4850) $PN 2
J 0
(-2138 4863);
DISPLAY 0.787234 (-2138 4863);
PAINT ORANGE (-2138 4863);
FORCEPROP 1 LAST TOLERANCE 1%
J 0
(-2100 4975);
DISPLAY 0.638298 (-2100 4975);
PAINT SKYBLUE (-2100 4975);
FORCEPROP 1 LAST LOCATION R6W50
J 0
(-2100 5075);
DISPLAY 0.638298 (-2100 5075);
PAINT SKYBLUE (-2100 5075);
FORCEPROP 1 LAST PACK_TYPE 0402
J 0
(-2100 4875);
DISPLAY 0.638298 (-2100 4875);
PAINT SKYBLUE (-2100 4875);
FORCEPROP 1 LAST WATTAGE 1/16W
J 0
(-2100 4925);
DISPLAY 0.638298 (-2100 4925);
PAINT SKYBLUE (-2100 4925);
FORCEPROP 0 LAST POP NOPOP
J 0
(-2100 4725);
DISPLAY 0.638298 (-2100 4725);
PAINT RED (-2100 4725);
FORCEPROP 1 LAST PART_NUMBER G21796-072
J 0
(-2100 4825);
DISPLAY 0.638298 (-2100 4825);
PAINT BLUE (-2100 4825);
FORCEPROP 1 LAST MATERIAL CHIP
J 0
(-2100 4775);
DISPLAY 0.638298 (-2100 4775);
PAINT SKYBLUE (-2100 4775);
FORCEPROP 1 LAST PATH I178
R 3
J 0
(-2000 5000);
DISPLAY 0.978723 (-2000 5000);
PAINT WHITE (-2000 5000);
DISPLAY INVISIBLE (-2000 5000);
FORCEPROP 2 LAST CDS_LIB mstr_discrete
R 2
J 0
(-2150 4950);
PAINT MONO (-2150 4950);
DISPLAY INVISIBLE (-2150 4950);
FORCEPROP 2 LAST SEC_TYPE 0402
R 2
J 0
(-2200 4775);
DISPLAY 1.021277 (-2200 4775);
PAINT ORANGE (-2200 4775);
DISPLAY INVISIBLE (-2200 4775);
FORCEPROP 0 LAST SEC 1
R 3
J 0
(-2200 4775);
DISPLAY 0.680851 (-2200 4775);
PAINT MONO (-2200 4775);
DISPLAY INVISIBLE (-2200 4775);
FORCEADD P3V3_STBY..1
(-2150 5200);
FORCEPROP 3 LASTPIN (-2150 5150) SIG_NAME P3V3_STBY\g
J 0
(-2140 5160);
DISPLAY 0.659574 (-2140 5160);
PAINT MONO (-2140 5160);
DISPLAY INVISIBLE (-2140 5160);
FORCEPROP 1 LAST PATH I179
J 0
(-2105 5202);
DISPLAY 0.340426 (-2105 5202);
PAINT GREEN (-2105 5202);
DISPLAY INVISIBLE (-2105 5202);
FORCEPROP 1 LAST HDL_POWER P3V3_STBY
J 0
(-2450 5075);
DISPLAY 0.872340 (-2450 5075);
PAINT ORANGE (-2450 5075);
DISPLAY INVISIBLE (-2450 5075);
FORCEPROP 1 LAST BODY_TYPE PLUMBING
J 0
(-2195 5157);
DISPLAY 0.340426 (-2195 5157);
PAINT GREEN (-2195 5157);
DISPLAY INVISIBLE (-2195 5157);
FORCEPROP 1 LAST VOLTAGE 3.3V
J 0
(-2195 5157);
DISPLAY 0.340426 (-2195 5157);
PAINT SKYBLUE (-2195 5157);
DISPLAY INVISIBLE (-2195 5157);
FORCEPROP 1 LAST SIZE 1B
J 0
(-2105 5222);
DISPLAY 0.340426 (-2105 5222);
PAINT GREEN (-2105 5222);
DISPLAY INVISIBLE (-2105 5222);
FORCEPROP 2 LAST CDS_LIB mstr_symbols
J 0
(-2150 5200);
PAINT MONO (-2150 5200);
DISPLAY INVISIBLE (-2150 5200);
FORCEADD CHOKE_4PIN..1
(-5500 5025);
FORCEPROP 2 LASTPIN (-5750 4925) $PN 2
J 2
(-5760 4935);
DISPLAY 0.808511 (-5760 4935);
PAINT ORANGE (-5760 4935);
FORCEPROP 2 LASTPIN (-5750 5125) $PN 1
J 2
(-5760 5135);
DISPLAY 0.808511 (-5760 5135);
PAINT ORANGE (-5760 5135);
FORCEPROP 1 LAST VALUE 90 OHM
J 0
(-5700 5275);
DISPLAY 0.638298 (-5700 5275);
PAINT SKYBLUE (-5700 5275);
FORCEPROP 1 LAST MATERIAL IND
J 0
(-5700 5325);
DISPLAY 0.638298 (-5700 5325);
PAINT SKYBLUE (-5700 5325);
FORCEPROP 1 LAST LOCATION L1M2
J 0
(-5700 5375);
DISPLAY 0.638298 (-5700 5375);
PAINT SKYBLUE (-5700 5375);
FORCEPROP 2 LASTPIN (-5300 5125) $PN 4
J 0
(-5290 5135);
DISPLAY 0.808511 (-5290 5135);
PAINT ORANGE (-5290 5135);
FORCEPROP 1 LAST PART_NUMBER 752402-015
J 0
(-5700 4785);
DISPLAY 0.638298 (-5700 4785);
PAINT BLUE (-5700 4785);
FORCEPROP 2 LASTPIN (-5300 4925) $PN 3
J 0
(-5290 4935);
DISPLAY 0.808511 (-5290 4935);
PAINT ORANGE (-5290 4935);
FORCEPROP 1 LAST PACK_TYPE SMLF
J 0
(-5700 5425);
DISPLAY 0.978723 (-5700 5425);
PAINT WHITE (-5700 5425);
DISPLAY INVISIBLE (-5700 5425);
FORCEPROP 2 LAST SEC 1
J 0
(-5700 5425);
DISPLAY 0.680851 (-5700 5425);
PAINT MONO (-5700 5425);
DISPLAY INVISIBLE (-5700 5425);
FORCEPROP 2 LAST SEC_TYPE SMLF
J 0
(-5700 5425);
DISPLAY 1.021277 (-5700 5425);
PAINT ORANGE (-5700 5425);
DISPLAY INVISIBLE (-5700 5425);
FORCEPROP 2 LAST CDS_LIB mstr_discrete
J 0
(-5500 5025);
DISPLAY INVISIBLE (-5500 5025);
FORCEPROP 1 LAST PATH I181
J 2
(-5720 5375);
DISPLAY 0.978723 (-5720 5375);
PAINT WHITE (-5720 5375);
DISPLAY INVISIBLE (-5720 5375);
FORCEADD NC7SB3157..1
(-750 1850);
FORCEPROP 2 LASTPIN (-400 1700) $PN 2
J 0
(-390 1710);
DISPLAY 0.617021 (-390 1710);
PAINT WHITE (-390 1710);
FORCEPROP 1 LAST LOCATION U6W12
J 0
(-1050 2125);
DISPLAY 0.617021 (-1050 2125);
PAINT AQUA (-1050 2125);
FORCEPROP 2 LASTPIN (-1100 2000) $PN 6
J 2
(-1110 2010);
DISPLAY 0.617021 (-1110 2010);
PAINT WHITE (-1110 2010);
FORCEPROP 2 LASTPIN (-1100 1900) $PN 3
J 2
(-1110 1910);
DISPLAY 0.617021 (-1110 1910);
PAINT WHITE (-1110 1910);
FORCEPROP 2 LASTPIN (-400 1850) $PN 4
J 0
(-390 1860);
DISPLAY 0.617021 (-390 1860);
PAINT WHITE (-390 1860);
FORCEPROP 2 LASTPIN (-1100 1800) $PN 1
J 2
(-1110 1810);
DISPLAY 0.617021 (-1110 1810);
PAINT WHITE (-1110 1810);
FORCEPROP 1 LAST PACK_TYPE SMLF
J 0
(-925 1600);
DISPLAY 0.617021 (-925 1600);
PAINT SKYBLUE (-925 1600);
FORCEPROP 1 LAST MATERIAL IC
J 0
(-1050 1600);
DISPLAY 0.617021 (-1050 1600);
PAINT SKYBLUE (-1050 1600);
FORCEPROP 2 LASTPIN (-1100 1700) $PN 5
J 2
(-1110 1710);
DISPLAY 0.617021 (-1110 1710);
PAINT WHITE (-1110 1710);
FORCEPROP 1 LAST PART_NUMBER C99406-001
J 0
(-1050 2075);
DISPLAY 0.617021 (-1050 2075);
PAINT BLUE (-1050 2075);
FORCEPROP 1 LAST PATH I182
J 0
(-675 1600);
DISPLAY 0.851064 (-675 1600);
PAINT WHITE (-675 1600);
DISPLAY INVISIBLE (-675 1600);
FORCEPROP 2 LAST BOM_COST DEBUG
J 2
(-1050 2225);
DISPLAY 1.617021 (-1050 2225);
PAINT WHITE (-1050 2225);
DISPLAY INVISIBLE (-1050 2225);
FORCEPROP 2 LAST CDS_LIB mstr_analog
J 0
(-750 1850);
DISPLAY 2.212766 (-750 1850);
PAINT ORANGE (-750 1850);
DISPLAY INVISIBLE (-750 1850);
FORCEPROP 2 LAST CDS_SEC 1
J 2
(-1050 2175);
PAINT MONO (-1050 2175);
DISPLAY INVISIBLE (-1050 2175);
FORCEPROP 2 LAST $SEC 1
J 2
(-1050 2175);
PAINT MONO (-1050 2175);
DISPLAY INVISIBLE (-1050 2175);
FORCEPROP 2 LAST ROOM DEBUG
J 2
(-1050 2175);
DISPLAY 1.617021 (-1050 2175);
PAINT WHITE (-1050 2175);
DISPLAY INVISIBLE (-1050 2175);
FORCEADD GND..1
(-350 1650);
FORCEPROP 3 LASTPIN (-350 1700) SIG_NAME GND\g
J 0
(-340 1710);
DISPLAY 0.659574 (-340 1710);
PAINT MONO (-340 1710);
DISPLAY INVISIBLE (-340 1710);
FORCEPROP 1 LAST PATH I183
J 0
(-275 1650);
DISPLAY 0.872340 (-275 1650);
PAINT AQUA (-275 1650);
DISPLAY INVISIBLE (-275 1650);
FORCEPROP 1 LAST HDL_POWER GND
J 0
(-350 1800);
DISPLAY 1.170213 (-350 1800);
PAINT GREEN (-350 1800);
DISPLAY INVISIBLE (-350 1800);
FORCEPROP 1 LAST BODY_TYPE PLUMBING
J 0
(-395 1607);
DISPLAY 0.340426 (-395 1607);
PAINT GREEN (-395 1607);
DISPLAY INVISIBLE (-395 1607);
FORCEPROP 1 LAST VOLTAGE 0.0V
J 0
(-395 1607);
DISPLAY 0.340426 (-395 1607);
PAINT GREEN (-395 1607);
DISPLAY INVISIBLE (-395 1607);
FORCEPROP 2 LAST CDS_LIB mstr_symbols
J 0
(-350 1650);
PAINT MONO (-350 1650);
DISPLAY INVISIBLE (-350 1650);
FORCEPROP 1 LAST SIZE 1B
J 0
(-275 1600);
DISPLAY 1.170213 (-275 1600);
PAINT AQUA (-275 1600);
DISPLAY INVISIBLE (-275 1600);
FORCEADD RES..1
(-5650 5550);
FORCEPROP 1 LAST WATTAGE 1/16W
J 0
(-5225 5600);
DISPLAY 0.510638 (-5225 5600);
PAINT SKYBLUE (-5225 5600);
FORCEPROP 1 LAST VALUE 0.0
J 2
(-5475 5600);
DISPLAY 0.617021 (-5475 5600);
PAINT SKYBLUE (-5475 5600);
FORCEPROP 1 LAST MATERIAL CHIP
J 0
(-5875 5575);
DISPLAY 0.617021 (-5875 5575);
PAINT SKYBLUE (-5875 5575);
FORCEPROP 1 LAST TOLERANCE 5%
J 0
(-5725 5500);
DISPLAY 0.617021 (-5725 5500);
PAINT SKYBLUE (-5725 5500);
FORCEPROP 1 LASTPIN (-5750 5550) $PN 1
J 0
(-5738 5562);
DISPLAY 0.617021 (-5738 5562);
PAINT WHITE (-5738 5562);
FORCEPROP 1 LASTPIN (-5550 5550) $PN 2
J 0
(-5588 5562);
DISPLAY 0.617021 (-5588 5562);
PAINT WHITE (-5588 5562);
FORCEPROP 1 LAST LOCATION R1M6
J 0
(-5700 5600);
DISPLAY 0.617021 (-5700 5600);
PAINT AQUA (-5700 5600);
FORCEPROP 0 LAST POP NOPOP
J 0
(-5125 5600);
DISPLAY 1.021277 (-5125 5600);
PAINT RED (-5125 5600);
FORCEPROP 1 LAST PACK_TYPE 0402
J 0
(-5550 5500);
DISPLAY 0.617021 (-5550 5500);
PAINT SKYBLUE (-5550 5500);
FORCEPROP 1 LAST PART_NUMBER G21497-005
J 0
(-5450 5600);
DISPLAY 0.510638 (-5450 5600);
PAINT BLUE (-5450 5600);
FORCEPROP 2 LAST CDS_LOCATION R1M6
J 0
(-5700 5600);
DISPLAY 0.617021 (-5700 5600);
PAINT AQUA (-5700 5600);
DISPLAY INVISIBLE (-5700 5600);
FORCEPROP 2 LAST CDS_LIB mstr_discrete
J 0
(-5650 5550);
PAINT MONO (-5650 5550);
DISPLAY INVISIBLE (-5650 5550);
FORCEPROP 0 LAST ROOM USB
J 0
(-5475 5650);
DISPLAY 1.021277 (-5475 5650);
PAINT ORANGE (-5475 5650);
DISPLAY INVISIBLE (-5475 5650);
FORCEPROP 0 LAST BOM_COST MIO_USB
J 0
(-5475 5700);
DISPLAY 1.021277 (-5475 5700);
PAINT ORANGE (-5475 5700);
DISPLAY INVISIBLE (-5475 5700);
FORCEPROP 1 LAST PATH I31
J 0
(-5700 5700);
DISPLAY 0.978723 (-5700 5700);
PAINT WHITE (-5700 5700);
DISPLAY INVISIBLE (-5700 5700);
FORCEPROP 2 LAST SEC_TYPE 0402
J 0
(-5700 5750);
DISPLAY 1.021277 (-5700 5750);
PAINT ORANGE (-5700 5750);
DISPLAY INVISIBLE (-5700 5750);
FORCEPROP 2 LAST SEC 1
J 0
(-5700 5750);
DISPLAY 0.680851 (-5700 5750);
PAINT MONO (-5700 5750);
DISPLAY INVISIBLE (-5700 5750);
FORCEADD OFFPAGE..6
(-6500 5125);
FORCEPROP 2 LAST $XR0 115 
J 0
(-6810 5125);
DISPLAY 0.638298 (-6810 5125);
PAINT MONO (-6810 5125);
FORCEPROP 1 LAST COMMENT_BODY TRUE
J 0
(-6400 5050);
DISPLAY 0.872340 (-6400 5050);
PAINT PEACH (-6400 5050);
DISPLAY INVISIBLE (-6400 5050);
FORCEPROP 1 LAST OFFPAGE TRUE
J 0
(-6175 5000);
PAINT GREEN (-6175 5000);
DISPLAY INVISIBLE (-6175 5000);
FORCEPROP 2 LAST PATH I46
J 0
(-6450 5200);
DISPLAY 1.021277 (-6450 5200);
PAINT ORANGE (-6450 5200);
DISPLAY INVISIBLE (-6450 5200);
FORCEPROP 2 LAST CDS_LIB mstr_standard
J 0
(-6500 5125);
PAINT MONO (-6500 5125);
DISPLAY INVISIBLE (-6500 5125);
FORCEADD OFFPAGE..6
(-6500 4925);
FORCEPROP 2 LAST $XR0 115 
J 0
(-6810 4925);
DISPLAY 0.638298 (-6810 4925);
PAINT MONO (-6810 4925);
FORCEPROP 1 LAST COMMENT_BODY TRUE
J 0
(-6400 4850);
DISPLAY 0.872340 (-6400 4850);
PAINT PEACH (-6400 4850);
DISPLAY INVISIBLE (-6400 4850);
FORCEPROP 1 LAST OFFPAGE TRUE
J 0
(-6175 4800);
PAINT GREEN (-6175 4800);
DISPLAY INVISIBLE (-6175 4800);
FORCEPROP 2 LAST PATH I47
J 0
(-6450 5000);
DISPLAY 1.021277 (-6450 5000);
PAINT ORANGE (-6450 5000);
DISPLAY INVISIBLE (-6450 5000);
FORCEPROP 2 LAST CDS_LIB mstr_standard
J 0
(-6500 4925);
PAINT MONO (-6500 4925);
DISPLAY INVISIBLE (-6500 4925);
FORCEADD CONN9_H51826001..2
(-1300 4550);
FORCEPROP 2 LASTPIN (-1900 4450) $PN 3
J 2
(-1910 4460);
DISPLAY 0.617021 (-1910 4460);
PAINT MONO (-1910 4460);
FORCEPROP 2 LASTPIN (-1900 4700) $PN 1
J 2
(-1910 4710);
DISPLAY 0.617021 (-1910 4710);
PAINT MONO (-1910 4710);
FORCEPROP 1 LAST MATERIAL CONN
J 0
(-1850 4950);
DISPLAY 0.617021 (-1850 4950);
PAINT SKYBLUE (-1850 4950);
FORCEPROP 2 LASTPIN (-1900 4400) $PN 2
J 2
(-1910 4410);
DISPLAY 0.617021 (-1910 4410);
PAINT MONO (-1910 4410);
FORCEPROP 2 LASTPIN (-1900 4300) $PN MH1
J 2
(-1910 4310);
DISPLAY 0.617021 (-1910 4310);
PAINT MONO (-1910 4310);
FORCEPROP 2 LASTPIN (-1900 4250) $PN MH2
J 2
(-1910 4260);
DISPLAY 0.617021 (-1910 4260);
PAINT MONO (-1910 4260);
FORCEPROP 1 LAST PART_NUMBER H51826-001
J 0
(-1850 4150);
DISPLAY 0.617021 (-1850 4150);
PAINT BLUE (-1850 4150);
FORCEPROP 2 LASTPIN (-650 4300) $PN MH3
J 0
(-640 4310);
DISPLAY 0.617021 (-640 4310);
PAINT MONO (-640 4310);
FORCEPROP 2 LASTPIN (-650 4250) $PN MH4
J 0
(-640 4260);
DISPLAY 0.617021 (-640 4260);
PAINT MONO (-640 4260);
FORCEPROP 2 LASTPIN (-650 4400) $PN 7
J 0
(-640 4410);
DISPLAY 0.617021 (-640 4410);
PAINT MONO (-640 4410);
FORCEPROP 2 LASTPIN (-650 4600) $PN 6
J 0
(-640 4610);
DISPLAY 0.617021 (-640 4610);
PAINT MONO (-640 4610);
FORCEPROP 2 LASTPIN (-1900 4550) $PN 8
J 2
(-1910 4560);
DISPLAY 0.617021 (-1910 4560);
PAINT MONO (-1910 4560);
FORCEPROP 2 LASTPIN (-650 4550) $PN 5
J 0
(-640 4560);
DISPLAY 0.617021 (-640 4560);
PAINT MONO (-640 4560);
FORCEPROP 2 LASTPIN (-650 4450) $PN 4
J 0
(-640 4460);
DISPLAY 0.617021 (-640 4460);
PAINT MONO (-640 4460);
FORCEPROP 2 LASTPIN (-1900 4600) $PN 9
J 2
(-1910 4610);
DISPLAY 0.617021 (-1910 4610);
PAINT MONO (-1910 4610);
FORCEPROP 1 LAST LOCATION J9B1
J 0
(-1850 5000);
DISPLAY 0.617021 (-1850 5000);
PAINT AQUA (-1850 5000);
FORCEPROP 2 LAST CDS_LIB mstr_conn
J 0
(-1300 4550);
PAINT ORANGE (-1300 4550);
DISPLAY INVISIBLE (-1300 4550);
FORCEPROP 2 LAST $SEC 1
J 0
(-1850 5050);
PAINT MONO (-1850 5050);
DISPLAY INVISIBLE (-1850 5050);
FORCEPROP 2 LAST CDS_SEC 1
J 0
(-1850 5050);
PAINT MONO (-1850 5050);
DISPLAY INVISIBLE (-1850 5050);
FORCEPROP 1 LAST PACK_TYPE PIP2
J 0
(-1850 5050);
PAINT SKYBLUE (-1850 5050);
DISPLAY INVISIBLE (-1850 5050);
FORCEPROP 2 LAST CDS_LOCATION J9B1
J 0
(-1850 5000);
DISPLAY 0.617021 (-1850 5000);
PAINT AQUA (-1850 5000);
DISPLAY INVISIBLE (-1850 5000);
FORCEPROP 1 LAST PATH I69
J 0
(-1300 4950);
PAINT GREEN (-1300 4950);
DISPLAY INVISIBLE (-1300 4950);
FORCEPROP 2 LAST ROOM USB_REAR
J 0
(-1550 4900);
DISPLAY 1.021277 (-1550 4900);
PAINT ORANGE (-1550 4900);
DISPLAY INVISIBLE (-1550 4900);
FORCEADD GND..1
(-2550 4075);
FORCEPROP 3 LASTPIN (-2550 4125) SIG_NAME GND\g
J 0
(-2540 4135);
DISPLAY 0.659574 (-2540 4135);
PAINT MONO (-2540 4135);
DISPLAY INVISIBLE (-2540 4135);
FORCEPROP 1 LAST PATH I70
J 0
(-2475 4075);
DISPLAY 0.872340 (-2475 4075);
PAINT AQUA (-2475 4075);
DISPLAY INVISIBLE (-2475 4075);
FORCEPROP 2 LAST CDS_LIB mstr_symbols
J 0
(-2550 4075);
PAINT ORANGE (-2550 4075);
DISPLAY INVISIBLE (-2550 4075);
FORCEPROP 1 LAST SIZE 1B
J 0
(-2475 4025);
DISPLAY 0.872340 (-2475 4025);
PAINT AQUA (-2475 4025);
DISPLAY INVISIBLE (-2475 4025);
FORCEPROP 1 LAST VOLTAGE 0.0V
J 0
(-2595 4032);
DISPLAY 0.340426 (-2595 4032);
PAINT SKYBLUE (-2595 4032);
DISPLAY INVISIBLE (-2595 4032);
FORCEPROP 1 LAST BODY_TYPE PLUMBING
J 0
(-2595 4032);
DISPLAY 0.340426 (-2595 4032);
PAINT GREEN (-2595 4032);
DISPLAY INVISIBLE (-2595 4032);
FORCEPROP 1 LAST HDL_POWER GND
J 0
(-2550 4225);
DISPLAY 0.702128 (-2550 4225);
PAINT GREEN (-2550 4225);
DISPLAY INVISIBLE (-2550 4225);
FORCEADD GND..1
(-50 4100);
FORCEPROP 3 LASTPIN (-50 4150) SIG_NAME GND\g
J 0
(-40 4160);
DISPLAY 0.659574 (-40 4160);
PAINT MONO (-40 4160);
DISPLAY INVISIBLE (-40 4160);
FORCEPROP 1 LAST PATH I71
J 0
(25 4100);
DISPLAY 0.872340 (25 4100);
PAINT AQUA (25 4100);
DISPLAY INVISIBLE (25 4100);
FORCEPROP 2 LAST CDS_LIB mstr_symbols
J 0
(-50 4100);
PAINT ORANGE (-50 4100);
DISPLAY INVISIBLE (-50 4100);
FORCEPROP 1 LAST SIZE 1B
J 0
(25 4050);
DISPLAY 0.872340 (25 4050);
PAINT AQUA (25 4050);
DISPLAY INVISIBLE (25 4050);
FORCEPROP 1 LAST VOLTAGE 0.0V
J 0
(-95 4057);
DISPLAY 0.340426 (-95 4057);
PAINT SKYBLUE (-95 4057);
DISPLAY INVISIBLE (-95 4057);
FORCEPROP 1 LAST BODY_TYPE PLUMBING
J 0
(-95 4057);
DISPLAY 0.340426 (-95 4057);
PAINT GREEN (-95 4057);
DISPLAY INVISIBLE (-95 4057);
FORCEPROP 1 LAST HDL_POWER GND
J 0
(-50 4250);
DISPLAY 0.702128 (-50 4250);
PAINT GREEN (-50 4250);
DISPLAY INVISIBLE (-50 4250);
FORCEADD OFFPAGE..1
(-2600 4700);
FORCEPROP 2 LAST $XR0 176 
J 0
(-2882 4700);
DISPLAY 0.638298 (-2882 4700);
PAINT MONO (-2882 4700);
FORCEPROP 2 LAST PATH I75
J 0
(-2550 4775);
DISPLAY 1.021277 (-2550 4775);
PAINT ORANGE (-2550 4775);
DISPLAY INVISIBLE (-2550 4775);
FORCEPROP 2 LAST CDS_LIB mstr_standard
J 0
(-2600 4700);
PAINT ORANGE (-2600 4700);
DISPLAY INVISIBLE (-2600 4700);
FORCEPROP 1 LAST OFFPAGE TRUE
J 0
(-2275 4575);
DISPLAY 0.872340 (-2275 4575);
PAINT GREEN (-2275 4575);
DISPLAY INVISIBLE (-2275 4575);
FORCEPROP 1 LAST COMMENT_BODY TRUE
J 0
(-2475 4600);
DISPLAY 0.872340 (-2475 4600);
PAINT GREEN (-2475 4600);
DISPLAY INVISIBLE (-2475 4600);
FORCEADD DIODEAC_DUAL_ARRAY..7
(-3950 4500);
FORCEPROP 1 LAST MATERIAL IC
J 0
(-4250 4800);
DISPLAY 0.617021 (-4250 4800);
PAINT SKYBLUE (-4250 4800);
FORCEPROP 1 LAST LOCATION CR1M2
J 0
(-4250 4850);
DISPLAY 0.617021 (-4250 4850);
PAINT AQUA (-4250 4850);
FORCEPROP 2 LASTPIN (-3600 4350) $PN 3
J 0
(-3590 4360);
DISPLAY 0.617021 (-3590 4360);
PAINT ORANGE (-3590 4360);
FORCEPROP 2 LASTPIN (-3600 4500) $PN 8
J 0
(-3590 4510);
DISPLAY 0.617021 (-3590 4510);
PAINT ORANGE (-3590 4510);
FORCEPROP 2 LASTPIN (-3600 4450) $PN 9
J 0
(-3590 4460);
DISPLAY 0.617021 (-3590 4460);
PAINT ORANGE (-3590 4460);
FORCEPROP 1 LAST PART_NUMBER G18435-001
J 0
(-4250 4200);
DISPLAY 0.617021 (-4250 4200);
PAINT BLUE (-4250 4200);
FORCEPROP 2 LASTPIN (-4300 4500) $PN 2
J 2
(-4310 4510);
DISPLAY 0.617021 (-4310 4510);
PAINT ORANGE (-4310 4510);
FORCEPROP 2 LASTPIN (-3600 4600) $PN 6
J 0
(-3590 4610);
DISPLAY 0.617021 (-3590 4610);
PAINT ORANGE (-3590 4610);
FORCEPROP 2 LASTPIN (-4300 4600) $PN 5
J 2
(-4310 4610);
DISPLAY 0.617021 (-4310 4610);
PAINT ORANGE (-4310 4610);
FORCEPROP 2 LASTPIN (-4300 4550) $PN 4
J 2
(-4310 4560);
DISPLAY 0.617021 (-4310 4560);
PAINT ORANGE (-4310 4560);
FORCEPROP 2 LASTPIN (-4300 4450) $PN 1
J 2
(-4310 4460);
DISPLAY 0.617021 (-4310 4460);
PAINT ORANGE (-4310 4460);
FORCEPROP 2 LASTPIN (-3600 4550) $PN 7
J 0
(-3590 4560);
DISPLAY 0.617021 (-3590 4560);
PAINT ORANGE (-3590 4560);
FORCEPROP 1 LAST VALUE ESD3V3U4ULC
J 1
(-3975 4675);
DISPLAY 0.617021 (-3975 4675);
PAINT SKYBLUE (-3975 4675);
FORCEPROP 2 LAST CDS_LIB mstr_discrete
J 0
(-3950 4500);
PAINT MONO (-3950 4500);
DISPLAY INVISIBLE (-3950 4500);
FORCEPROP 0 LAST ROOM USB_REAR
J 0
(-4200 4850);
DISPLAY 1.021277 (-4200 4850);
PAINT ORANGE (-4200 4850);
DISPLAY INVISIBLE (-4200 4850);
FORCEPROP 2 LAST CDS_LOCATION CR1M2
J 0
(-4250 4850);
DISPLAY 0.617021 (-4250 4850);
PAINT AQUA (-4250 4850);
DISPLAY INVISIBLE (-4250 4850);
FORCEPROP 2 LAST SEC 1
J 0
(-4250 4900);
DISPLAY 0.680851 (-4250 4900);
PAINT MONO (-4250 4900);
DISPLAY INVISIBLE (-4250 4900);
FORCEPROP 2 LAST SEC_TYPE SM9
J 0
(-4250 4900);
DISPLAY 1.021277 (-4250 4900);
PAINT ORANGE (-4250 4900);
DISPLAY INVISIBLE (-4250 4900);
FORCEPROP 1 LAST PACK_TYPE SM9
J 0
(-4250 4900);
PAINT SKYBLUE (-4250 4900);
DISPLAY INVISIBLE (-4250 4900);
FORCEPROP 0 LAST BOM_COST MIO_USB
J 0
(-4200 4900);
DISPLAY 1.021277 (-4200 4900);
PAINT ORANGE (-4200 4900);
DISPLAY INVISIBLE (-4200 4900);
FORCEPROP 1 LAST PATH I98
J 0
(-3950 4800);
PAINT GREEN (-3950 4800);
DISPLAY INVISIBLE (-3950 4800);
FORCEADD GND..1
(-3550 4250);
FORCEPROP 3 LASTPIN (-3550 4300) SIG_NAME GND\g
J 0
(-3540 4310);
DISPLAY 0.659574 (-3540 4310);
PAINT MONO (-3540 4310);
DISPLAY INVISIBLE (-3540 4310);
FORCEPROP 1 LAST VOLTAGE 0.0V
J 0
(-3595 4207);
DISPLAY 0.340426 (-3595 4207);
PAINT SKYBLUE (-3595 4207);
DISPLAY INVISIBLE (-3595 4207);
FORCEPROP 1 LAST SIZE 1B
J 0
(-3475 4200);
DISPLAY 0.872340 (-3475 4200);
PAINT AQUA (-3475 4200);
DISPLAY INVISIBLE (-3475 4200);
FORCEPROP 2 LAST CDS_LIB mstr_symbols
J 0
(-3550 4250);
PAINT MONO (-3550 4250);
DISPLAY INVISIBLE (-3550 4250);
FORCEPROP 1 LAST PATH I99
J 0
(-3475 4250);
DISPLAY 0.872340 (-3475 4250);
PAINT AQUA (-3475 4250);
DISPLAY INVISIBLE (-3475 4250);
FORCEPROP 1 LAST BODY_TYPE PLUMBING
J 0
(-3595 4207);
DISPLAY 0.340426 (-3595 4207);
PAINT GREEN (-3595 4207);
DISPLAY INVISIBLE (-3595 4207);
FORCEPROP 1 LAST HDL_POWER GND
J 0
(-3550 4400);
DISPLAY 0.872340 (-3550 4400);
PAINT GREEN (-3550 4400);
DISPLAY INVISIBLE (-3550 4400);
FORCEADD CAD_NOTE..1
(225 1575);
FORCEPROP 0 LAST L2 TO IC
J 0
(75 1375);
DISPLAY 0.617021 (75 1375);
PAINT WHITE (75 1375);
FORCEPROP 0 LAST L1 PLACE CAP CLOSE
J 0
(75 1450);
DISPLAY 0.617021 (75 1450);
PAINT WHITE (75 1450);
FORCEPROP 1 LAST COMMENT_BODY TRUE
J 0
(250 1675);
DISPLAY 1.361702 (250 1675);
PAINT WHITE (250 1675);
DISPLAY INVISIBLE (250 1675);
FORCEPROP 2 LAST CDS_LIB mstr_symbols
J 0
(225 1575);
PAINT MONO (225 1575);
DISPLAY INVISIBLE (225 1575);
FORCEADD DESIGN_NOTE..1
(-7050 3650);
FORCEPROP 0 LAST L1 TPS2061
J 0
(-7250 3500);
DISPLAY 1.021277 (-7250 3500);
PAINT ORANGE (-7250 3500);
FORCEPROP 0 LAST L2 SHORT-CIRCUIT OUTPUT CURRENT 1.1A MIN - 1.9A MAX
J 0
(-7250 3425);
DISPLAY 1.021277 (-7250 3425);
PAINT ORANGE (-7250 3425);
FORCEPROP 1 LAST COMMENT_BODY TRUE
J 0
(-7025 3750);
DISPLAY 0.978723 (-7025 3750);
PAINT ORANGE (-7025 3750);
DISPLAY INVISIBLE (-7025 3750);
FORCEPROP 2 LAST CDS_LIB mstr_symbols
J 0
(-7050 3650);
PAINT ORANGE (-7050 3650);
DISPLAY INVISIBLE (-7050 3650);
FORCEADD DNS..2
(-4945 3945);
PAINT RED (-4945 3945);
FORCEPROP 2 LAST CDS_LIB mstr_misc
J 0
(-4945 3945);
PAINT MONO (-4945 3945);
DISPLAY INVISIBLE (-4945 3945);
FORCEPROP 1 LAST COMMENT_BODY TRUE
R 1
J 0
(-4870 3720);
DISPLAY 0.872340 (-4870 3720);
PAINT GREEN (-4870 3720);
DISPLAY INVISIBLE (-4870 3720);
FORCEADD CAD_NOTE..1
(-4750 5450);
FORCEPROP 0 LAST L1 OVERLAPPING FOOTPRINT
J 0
(-4900 5350);
DISPLAY 0.617021 (-4900 5350);
PAINT WHITE (-4900 5350);
FORCEPROP 2 LAST CDS_LIB mstr_symbols
J 0
(-4750 5450);
PAINT MONO (-4750 5450);
DISPLAY INVISIBLE (-4750 5450);
FORCEPROP 2 LAST ROOM ST_SATA
J 0
(-4900 5400);
PAINT WHITE (-4900 5400);
DISPLAY INVISIBLE (-4900 5400);
FORCEPROP 2 LAST BOM_COST MIO_CHASSIS
J 0
(-4900 5400);
PAINT WHITE (-4900 5400);
DISPLAY INVISIBLE (-4900 5400);
FORCEPROP 1 LAST COMMENT_BODY TRUE
J 0
(-4725 5550);
DISPLAY 1.319149 (-4725 5550);
PAINT PEACH (-4725 5550);
DISPLAY INVISIBLE (-4725 5550);
FORCEADD CAD_NOTE..1
(-4275 2875);
FORCEPROP 0 LAST L1 PLACE AS CLOSE AS POSSIBLE TO USB CONNECTOR
J 0
(-4425 2750);
DISPLAY 0.765957 (-4425 2750);
PAINT WHITE (-4425 2750);
FORCEPROP 1 LAST COMMENT_BODY TRUE
J 0
(-4250 2975);
DISPLAY 1.319149 (-4250 2975);
PAINT PEACH (-4250 2975);
DISPLAY INVISIBLE (-4250 2975);
FORCEPROP 2 LAST CDS_LIB mstr_symbols
J 0
(-4275 2875);
PAINT ORANGE (-4275 2875);
DISPLAY INVISIBLE (-4275 2875);
FORCEPROP 2 LAST ROOM ST_SATA
J 0
(-4425 2825);
PAINT WHITE (-4425 2825);
DISPLAY INVISIBLE (-4425 2825);
FORCEPROP 2 LAST BOM_COST MIO_CHASSIS
J 0
(-4425 2825);
PAINT WHITE (-4425 2825);
DISPLAY INVISIBLE (-4425 2825);
FORCEADD DNS..2
(-5645 3020);
PAINT RED (-5645 3020);
FORCEPROP 1 LAST COMMENT_BODY TRUE
R 1
J 0
(-5570 2795);
DISPLAY 0.872340 (-5570 2795);
PAINT GREEN (-5570 2795);
DISPLAY INVISIBLE (-5570 2795);
FORCEPROP 2 LAST CDS_LIB mstr_misc
J 0
(-5645 3020);
PAINT MONO (-5645 3020);
DISPLAY INVISIBLE (-5645 3020);
FORCEADD INTEL_CORP_BPAGE..1
(675 800);
FORCEPROP 1 LAST CDS_CON_LAST_MODIFIED Fri Jun 16 17:49:05 2017
J 0
(-750 1125);
PAINT ORANGE (-750 1125);
DISPLAY INVISIBLE (-750 1125);
FORCEPROP 2 LAST CUSTOM_TXT_CDS <XR_PAGE_TITLE>
J 0
(-7215 6050);
DISPLAY 0.638298 (-7215 6050);
PAINT PINK (-7215 6050);
DISPLAY INVISIBLE (-7215 6050);
FORCEPROP 2 LAST CUSTOM_TXT_CDS <CON_LAST_MODIFIED>
J 0
(-3325 900);
PAINT ORANGE (-3325 900);
FORCEPROP 2 LAST CUSTOM_TXT_CDS <CURRENT_DESIGN_SHEET> OF <TOTAL_DESIGN_SHEETS>
J 0
(175 825);
PAINT ORANGE (175 825);
FORCEPROP 1 LAST SCH_TITLE USB3 EXTERNAL RIGHT ANGLE CONNECTOR
J 0
(-7275 850);
DISPLAY 1.212766 (-7275 850);
PAINT YELLOW (-7275 850);
FORCEPROP 1 LAST COMMENT_BODY TRUE
J 0
(687 812);
DISPLAY 0.468085 (687 812);
PAINT PEACH (687 812);
DISPLAY INVISIBLE (687 812);
FORCEPROP 2 LAST CDS_LIB mstr_symbols
J 0
(675 800);
PAINT MONO (675 800);
DISPLAY INVISIBLE (675 800);
FORCEPROP 2 LAST PAGE_BORDER TRUE
J 0
(-7215 6050);
DISPLAY 0.638298 (-7215 6050);
PAINT PINK (-7215 6050);
DISPLAY INVISIBLE (-7215 6050);
FORCEPROP 2 LAST CDS_XR_PAGE_TITLE CR-176 : @BASEBOARD_FAB2_LIB.BASEBOARD_FAB2(SCH_1):PAGE176
J 0
(-7215 6050);
DISPLAY 0.638298 (-7215 6050);
PAINT PINK (-7215 6050);
DISPLAY INVISIBLE (-7215 6050);
WIRE 16 -1 (-4950 4050)(-4950 4100);
WIRE 16 -1 (-3750 3125)(-3750 3000);
WIRE 16 -1 (-3825 3125)(-3750 3125);
WIRE 16 -1 (-5225 3425)(-5225 3375);
WIRE 16 -1 (-3700 3775)(-3700 3825);
WIRE 16 -1 (-5200 2900)(-5200 2825);
WIRE 16 -1 (-3650 3050)(-3650 3000);
WIRE 16 -1 (-200 1400)(-200 1375);
WIRE 16 -1 (-200 1700)(-200 1650);
WIRE 16 -1 (-300 1650)(-200 1650);
WIRE 16 -1 (-200 1650)(-200 1600);
WIRE 16 -1 (-300 1500)(-300 1650);
WIRE 16 -1 (-1100 1500)(-300 1500);
WIRE 16 -1 (-1100 1700)(-1100 1500);
WIRE 16 -1 (-5350 4100)(-5350 4050);
WIRE 16 -1 (-1550 1750)(-1550 1700);
WIRE 16 -1 (-750 3525)(-750 3475);
WIRE 16 -1 (-1150 3525)(-750 3525);
WIRE 16 -1 (-650 2850)(-650 2900);
WIRE 16 -1 (-900 2850)(-650 2850);
WIRE 16 -1 (-900 2950)(-900 2850);
WIRE 16 -1 (-1200 2950)(-900 2950);
WIRE 16 -1 (-4175 1550)(-4175 1500);
WIRE 16 -1 (-3775 1550)(-3775 1500);
WIRE 16 -1 (-4175 1750)(-4175 1800);
WIRE 16 -1 (-3775 1750)(-3775 1800);
WIRE 16 -1 (-4400 2250)(-4400 2150);
WIRE 16 -1 (-4400 2150)(-4500 2150);
WIRE 16 -1 (-5400 2150)(-5400 2250);
WIRE 16 -1 (-5300 2150)(-5400 2150);
WIRE 16 -1 (-6100 2500)(-6100 2450);
WIRE 16 -1 (-6100 2450)(-5800 2450);
WIRE 16 -1 (-6100 2450)(-6100 2350);
WIRE 16 -1 (-5800 2450)(-5800 2350);
WIRE 16 -1 (-2150 5050)(-2150 5150);
WIRE 16 -1 (-400 1700)(-350 1700);
WIRE 16 -1 (-2550 4125)(-2550 4250);
WIRE 16 -1 (-2550 4250)(-2550 4300);
WIRE 16 -1 (-1900 4250)(-2550 4250);
WIRE 16 -1 (-2550 4300)(-1900 4300);
WIRE 16 -1 (-50 4150)(-50 4250);
WIRE 16 -1 (-50 4250)(-50 4300);
WIRE 16 -1 (-650 4250)(-50 4250);
WIRE 16 -1 (-50 4300)(-50 4450);
WIRE 16 -1 (-50 4300)(-650 4300);
WIRE 16 -1 (-50 4450)(-650 4450);
WIRE 16 -1 (-3550 4350)(-3550 4300);
WIRE 16 -1 (-3600 4350)(-3550 4350);
WIRE 3 682 (-2400 4050)(-2400 3750);
WIRE 3 682 (225 4050)(-2400 4050);
WIRE 3 682 (-2400 3750)(225 3750);
WIRE 3 682 (225 3750)(225 4050);
WIRE 3 682 (-2700 2325)(-2700 3700);
WIRE 3 682 (450 2325)(-2700 2325);
WIRE 3 682 (-2700 3700)(450 3700);
WIRE 3 682 (450 3700)(450 2325);
WIRE 16 -1 (-2350 1400)(-1550 1400);
FORCEPROP 2 LAST SIG_NAME SPA_MID_DBG2_RX_BUF
J 0
(-2285 1410);
DISPLAY 0.617021 (-2285 1410);
PAINT ORANGE (-2285 1410);
FORCEPROP 2 LASTPROP $XRERR UNIQUE?
J 0
(-2525 1410);
DISPLAY 0.638298 (-2525 1410);
PAINT MONO (-2525 1410);
DISPLAY INVISIBLE (-2525 1410);
WIRE 16 -1 (-1550 1500)(-1550 1400);
WIRE 16 -1 (-1250 1400)(-1550 1400);
WIRE 16 -1 (-1250 1800)(-1250 1400);
WIRE 16 -1 (-1100 1800)(-1250 1800);
WIRE 3 682 (-1600 1725)(-1600 1350);
WIRE 3 682 (-1200 1725)(-1600 1725);
WIRE 3 682 (-1600 1350)(-1200 1350);
WIRE 3 682 (-1200 1350)(-1200 1725);
WIRE 16 -1 (-400 1850)(200 1850);
FORCEPROP 2 LAST SIG_NAME SPA_MID_DBG_RX
J 0
(-260 1860);
DISPLAY 0.680851 (-260 1860);
PAINT ORANGE (-260 1860);
WIRE 16 -1 (-1100 1900)(-1700 1900);
FORCEPROP 2 LAST SIG_NAME SPA_MID_DBG1_RX
J 0
(-1635 1910);
DISPLAY 0.617021 (-1635 1910);
PAINT ORANGE (-1635 1910);
WIRE 16 -1 (-2500 1550)(-2500 1500);
WIRE 16 -1 (-3100 1550)(-2500 1550);
FORCEPROP 2 LAST SIG_NAME DEBUG_CARD2_PRSNT
J 0
(-3060 1560);
DISPLAY 0.680851 (-3060 1560);
PAINT ORANGE (-3060 1560);
FORCEPROP 2 LASTPROP $XR1 168 
J 0
(-3346 1550);
DISPLAY 0.638298 (-3346 1550);
PAINT MONO (-3346 1550);
FORCEPROP 2 LASTPROP $XR0 176 
J 0
(-3226 1550);
DISPLAY 0.638298 (-3226 1550);
PAINT MONO (-3226 1550);
WIRE 16 -1 (-1700 2000)(-1100 2000);
FORCEPROP 2 LAST SIG_NAME DEBUG_CARD2_PRSNT
J 0
(-1660 2010);
DISPLAY 0.680851 (-1660 2010);
PAINT ORANGE (-1660 2010);
FORCEPROP 2 LASTPROP $XR1 168 
J 0
(-1946 2000);
DISPLAY 0.638298 (-1946 2000);
PAINT MONO (-1946 2000);
FORCEPROP 2 LASTPROP $XR0 176 
J 0
(-1826 2000);
DISPLAY 0.638298 (-1826 2000);
PAINT MONO (-1826 2000);
WIRE 3 682 (-1800 1600)(-3250 1600);
WIRE 3 682 (-1800 1250)(-1800 1600);
WIRE 3 682 (-3250 1600)(-3250 1250);
WIRE 3 682 (-3250 1250)(-1800 1250);
WIRE 3 682 (-2750 4100)(-3100 4100);
WIRE 3 682 (-3100 5400)(-3100 4100);
WIRE 3 682 (-2750 4100)(-2750 1650);
WIRE 3 682 (-2750 1650)(-3350 1650);
WIRE 3 682 (-1050 5400)(-3100 5400);
WIRE 3 682 (-1050 5400)(-1050 4950);
WIRE 3 682 (-3350 1650)(-3350 1275);
WIRE 3 682 (525 1275)(-3350 1275);
WIRE 3 682 (-1050 4950)(525 4950);
WIRE 3 682 (525 4950)(525 1275);
WIRE 16 -1 (-2150 4850)(-2150 4600);
WIRE 16 -1 (-2150 4600)(-1900 4600);
WIRE 16 -1 (-2550 4600)(-2150 4600);
FORCEPROP 2 LAST SIG_NAME SPA_MID_DBG2_RX
J 0
(-2485 4610);
DISPLAY 0.617021 (-2485 4610);
PAINT ORANGE (-2485 4610);
WIRE 16 -1 (-5550 5550)(-5000 5550);
WIRE 16 -1 (-5300 5125)(-5000 5125);
WIRE 16 -1 (-5000 5550)(-5000 5125);
WIRE 16 -1 (-4825 4500)(-4300 4500);
WIRE 16 -1 (-4825 4500)(-4825 5125);
WIRE 16 -1 (-5000 5125)(-4825 5125);
WIRE 16 -1 (-2950 4400)(-1900 4400);
WIRE 16 -1 (-3600 4500)(-2950 4500);
WIRE 16 -1 (-2950 4500)(-2950 4400);
WIRE 16 -1 (-2950 5125)(-4825 5125);
FORCEPROP 2 LAST SIG_NAME USB2_P01_ESD_DN
J 1
(-4235 5135);
DISPLAY 0.617021 (-4235 5135);
PAINT ORANGE (-4235 5135);
FORCEPROP 2 LASTPROP $XRERR UNIQUE?
J 0
(-4475 5135);
DISPLAY 0.638298 (-4475 5135);
PAINT MONO (-4475 5135);
DISPLAY INVISIBLE (-4475 5135);
WIRE 16 -1 (-2950 5125)(-2950 4500);
WIRE 16 -1 (-3100 1400)(-2650 1400);
FORCEPROP 2 LAST SIG_NAME SPA_MID_DBG2_RX
J 0
(-3085 1410);
DISPLAY 0.617021 (-3085 1410);
PAINT ORANGE (-3085 1410);
FORCEPROP 2 LASTPROP $XR0 176 
J 0
(-3226 1400);
DISPLAY 0.638298 (-3226 1400);
PAINT MONO (-3226 1400);
WIRE 16 -1 (-5000 4600)(-5550 4600);
WIRE 16 -1 (-5300 4925)(-5000 4925);
WIRE 16 -1 (-5000 4600)(-5000 4925);
WIRE 16 -1 (-4300 4450)(-4875 4450);
WIRE 16 -1 (-4875 4925)(-4875 4450);
WIRE 16 -1 (-5000 4925)(-4875 4925);
WIRE 16 -1 (-3600 4450)(-3050 4450);
WIRE 16 -1 (-3050 4450)(-1900 4450);
WIRE 16 -1 (-3050 4925)(-4875 4925);
FORCEPROP 2 LAST SIG_NAME USB2_P01_ESD_DP
J 1
(-4235 4935);
DISPLAY 0.617021 (-4235 4935);
PAINT ORANGE (-4235 4935);
FORCEPROP 2 LASTPROP $XRERR UNIQUE?
J 0
(-4475 4935);
DISPLAY 0.638298 (-4475 4935);
PAINT MONO (-4475 4935);
DISPLAY INVISIBLE (-4475 4935);
WIRE 16 -1 (-3050 4925)(-3050 4450);
WIRE 16 3135 (-5950 5650)(-5950 4450);
WIRE 16 3135 (-4950 5650)(-5950 5650);
WIRE 16 3135 (-5950 4450)(-4950 4450);
WIRE 16 3135 (-4950 4450)(-4950 5650);
WIRE 16 -1 (-5900 4600)(-5750 4600);
WIRE 16 -1 (-5900 4600)(-5900 4925);
WIRE 16 -1 (-5900 4925)(-5750 4925);
WIRE 16 -1 (-6450 4925)(-5900 4925);
FORCEPROP 2 LAST SIG_NAME USB2_P01_DP
J 2
(-6085 4935);
DISPLAY 0.617021 (-6085 4935);
PAINT ORANGE (-6085 4935);
WIRE 3 682 (-6000 5700)(-6000 4400);
WIRE 3 682 (-4400 5700)(-6000 5700);
WIRE 3 682 (-6000 4400)(-4400 4400);
WIRE 3 682 (-4400 4400)(-4400 5700);
WIRE 16 -1 (-5750 5550)(-5900 5550);
WIRE 16 -1 (-5900 5550)(-5900 5125);
WIRE 16 -1 (-5900 5125)(-5750 5125);
WIRE 16 -1 (-6450 5125)(-5900 5125);
FORCEPROP 2 LAST SIG_NAME USB2_P01_DN
J 2
(-6085 5135);
DISPLAY 0.617021 (-6085 5135);
PAINT ORANGE (-6085 5135);
WIRE 3 2175 (-5550 3700)(-4650 3700);
WIRE 3 2175 (-5550 4250)(-5550 3700);
WIRE 3 2175 (-4650 3700)(-4650 4250);
WIRE 3 2175 (-4650 4250)(-5550 4250);
WIRE 3 682 (-7200 4250)(-7200 4150);
WIRE 3 682 (-5800 4250)(-7200 4250);
WIRE 3 682 (-7200 4150)(-5800 4150);
WIRE 3 682 (-5800 4150)(-5800 4250);
WIRE 68 -1 (-7200 3850)(-6550 3850);
WIRE 68 -1 (-6550 3850)(-5725 3850);
WIRE 68 -1 (-7200 3950)(-7200 3850);
WIRE 68 -1 (-7200 4050)(-7200 3950);
WIRE 68 -1 (-6550 4050)(-7200 4050);
WIRE 68 -1 (-6550 4050)(-6550 3850);
WIRE 68 -1 (-5725 4050)(-6550 4050);
WIRE 68 -1 (-7200 3950)(-5725 3950);
WIRE 68 -1 (-5725 3850)(-5725 3950);
WIRE 68 -1 (-5725 3950)(-5725 4050);
WIRE 3 2175 (-7150 3350)(-7150 2850);
WIRE 3 2175 (-5300 3350)(-7150 3350);
WIRE 3 2175 (-7150 2850)(-5300 2850);
WIRE 3 2175 (-5300 2850)(-5300 3350);
WIRE 16 -1 (-6650 3225)(-5750 3225);
FORCEPROP 0 LAST SIG_NAME FM_CPLD_USB_P0_EN_N
J 0
(-6610 3235);
DISPLAY 0.617021 (-6610 3235);
PAINT ORANGE (-6610 3235);
WIRE 16 -1 (-5350 3000)(-5550 3000);
WIRE 16 -1 (-5350 3000)(-5350 3225);
WIRE 16 -1 (-5550 3225)(-5350 3225);
WIRE 16 -1 (-5350 3225)(-5200 3225);
WIRE 16 -1 (-5200 3100)(-5200 3225);
WIRE 16 -1 (-4425 3225)(-5200 3225);
FORCEPROP 2 LAST SIG_NAME FM_USB_P0_EN_R_N
J 0
(-5085 3235);
DISPLAY 0.808511 (-5085 3235);
PAINT ORANGE (-5085 3235);
FORCEPROP 2 LASTPROP $XRERR UNIQUE?
J 0
(-5325 3235);
DISPLAY 0.638298 (-5325 3235);
PAINT MONO (-5325 3235);
DISPLAY INVISIBLE (-5325 3235);
WIRE 16 -1 (-4300 4600)(-4750 4600);
FORCEPROP 2 LAST SIG_NAME TP_USB_ESD_AC3
J 0
(-4735 4610);
DISPLAY 0.617021 (-4735 4610);
PAINT ORANGE (-4735 4610);
FORCEPROP 2 LASTPROP $XRERR UNIQUE?
J 0
(-4990 4600);
DISPLAY 0.638298 (-4990 4600);
PAINT MONO (-4990 4600);
DISPLAY INVISIBLE (-4990 4600);
WIRE 16 -1 (-4300 4550)(-4750 4550);
FORCEPROP 2 LAST SIG_NAME TP_USB_ESD_AC2
J 0
(-4735 4560);
DISPLAY 0.617021 (-4735 4560);
PAINT ORANGE (-4735 4560);
FORCEPROP 2 LASTPROP $XRERR UNIQUE?
J 0
(-4990 4550);
DISPLAY 0.638298 (-4990 4550);
PAINT MONO (-4990 4550);
DISPLAY INVISIBLE (-4990 4550);
WIRE 16 -1 (-2550 4700)(-1900 4700);
FORCEPROP 0 LAST VOLTAGE 5V
J 0
(-2525 4775);
DISPLAY 1.021277 (-2525 4775);
PAINT SKYBLUE (-2525 4775);
DISPLAY INVISIBLE (-2525 4775);
FORCEPROP 0 LAST SIG_NAME P5V_USB
J 0
(-2485 4710);
DISPLAY 0.617021 (-2485 4710);
PAINT ORANGE (-2485 4710);
WIRE 16 -1 (-1400 3150)(-800 3150);
FORCEPROP 2 LAST SIG_NAME SPA_MID_DBG2_TX_R
J 0
(-1335 3160);
DISPLAY 0.617021 (-1335 3160);
PAINT ORANGE (-1335 3160);
FORCEPROP 2 LASTPROP $XRERR UNIQUE?
J 0
(-1575 3160);
DISPLAY 0.638298 (-1575 3160);
PAINT MONO (-1575 3160);
DISPLAY INVISIBLE (-1575 3160);
WIRE 16 -1 (-1400 2600)(-825 2600);
FORCEPROP 2 LAST SIG_NAME SPA_MID_DBG1_TX_R
J 0
(-1360 2610);
DISPLAY 0.617021 (-1360 2610);
PAINT ORANGE (-1360 2610);
FORCEPROP 2 LASTPROP $XRERR UNIQUE?
J 0
(-1600 2610);
DISPLAY 0.638298 (-1600 2610);
PAINT MONO (-1600 2610);
DISPLAY INVISIBLE (-1600 2610);
WIRE 16 -1 (-1450 3850)(-2350 3850);
FORCEPROP 2 LAST SIG_NAME SMB_DEBUG_STBY_LVC3_SDA_R1
J 0
(-2335 3860);
DISPLAY 0.680851 (-2335 3860);
PAINT ORANGE (-2335 3860);
FORCEPROP 2 LASTPROP $XR0 176 
J 0
(-2506 3850);
DISPLAY 0.638298 (-2506 3850);
PAINT MONO (-2506 3850);
WIRE 16 -1 (-2550 4550)(-1900 4550);
FORCEPROP 2 LAST SIG_NAME SPA_MID_DBG2_TX
J 0
(-2485 4560);
DISPLAY 0.617021 (-2485 4560);
PAINT ORANGE (-2485 4560);
FORCEPROP 2 LASTPROP $XR0 176 
J 0
(-2856 4550);
DISPLAY 0.638298 (-2856 4550);
PAINT MONO (-2856 4550);
WIRE 16 -1 (-1450 3525)(-1350 3525);
WIRE 16 -1 (-1550 3625)(-1550 3250);
WIRE 16 -1 (-1550 3625)(-1450 3625);
WIRE 16 -1 (-1450 3625)(-1450 3525);
WIRE 16 -1 (-1450 3625)(-900 3625);
FORCEPROP 2 LAST SIG_NAME DEBUG_CARD2_PRSNT
J 0
(-1435 3635);
DISPLAY 0.680851 (-1435 3635);
PAINT ORANGE (-1435 3635);
FORCEPROP 2 LASTPROP $XR1 168 
J 0
(-750 3625);
DISPLAY 0.638298 (-750 3625);
PAINT MONO (-750 3625);
FORCEPROP 2 LASTPROP $XR0 176 
J 0
(-870 3625);
DISPLAY 0.638298 (-870 3625);
PAINT MONO (-870 3625);
WIRE 16 -1 (-6100 2050)(-7050 2050);
FORCEPROP 2 LAST SIG_NAME SMB_DEBUG_STBY_LVC3_SCL_CONN
J 0
(-6985 2060);
DISPLAY 0.680851 (-6985 2060);
PAINT ORANGE (-6985 2060);
FORCEPROP 2 LASTPROP $XR0 176 
J 0
(-7146 2050);
DISPLAY 0.638298 (-7146 2050);
PAINT MONO (-7146 2050);
WIRE 16 -1 (-6100 2150)(-6100 2050);
WIRE 16 -1 (-6100 2050)(-5300 2050);
WIRE 16 -1 (-5800 2000)(-7050 2000);
FORCEPROP 2 LAST SIG_NAME SMB_DEBUG_STBY_LVC3_SDA_CONN
J 0
(-6985 2010);
DISPLAY 0.680851 (-6985 2010);
PAINT ORANGE (-6985 2010);
FORCEPROP 2 LASTPROP $XR0 176 
J 0
(-7146 2000);
DISPLAY 0.638298 (-7146 2000);
PAINT MONO (-7146 2000);
WIRE 16 -1 (-5800 2000)(-5300 2000);
WIRE 16 -1 (-5800 2150)(-5800 2000);
WIRE 68 -1 (-4450 1950)(-4450 1400);
WIRE 68 -1 (-3450 1950)(-4450 1950);
WIRE 68 -1 (-4450 1400)(-3450 1400);
WIRE 68 -1 (-3450 1400)(-3450 1950);
WIRE 3 682 (-7250 2650)(-7250 1300);
WIRE 3 682 (-3400 2650)(-7250 2650);
WIRE 3 682 (-7250 1300)(-3400 1300);
WIRE 3 682 (-3400 1300)(-3400 2650);
WIRE 16 -1 (-1800 2600)(-1700 2600);
WIRE 16 -1 (-1800 3150)(-1800 2600);
WIRE 16 -1 (-1800 3150)(-1700 3150);
WIRE 16 -1 (-2275 3150)(-1800 3150);
FORCEPROP 2 LAST SIG_NAME SPA_MID_DBG_TX
J 0
(-2285 3160);
DISPLAY 0.702128 (-2285 3160);
PAINT ORANGE (-2285 3160);
WIRE 16 -1 (-1450 3900)(-2350 3900);
FORCEPROP 2 LAST SIG_NAME SMB_DEBUG_STBY_LVC3_SCL_R1
J 0
(-2335 3910);
DISPLAY 0.680851 (-2335 3910);
PAINT ORANGE (-2335 3910);
FORCEPROP 2 LASTPROP $XR0 176 
J 0
(-2506 3900);
DISPLAY 0.638298 (-2506 3900);
PAINT MONO (-2506 3900);
WIRE 16 -1 (-4500 2050)(-3650 2050);
FORCEPROP 2 LAST SIG_NAME SMB_DEBUG_STBY_LVC3_SCL_R1
J 0
(-4385 2060);
DISPLAY 0.680851 (-4385 2060);
PAINT ORANGE (-4385 2060);
FORCEPROP 2 LASTPROP $XR0 176 
J 0
(-3530 2050);
DISPLAY 0.638298 (-3530 2050);
PAINT MONO (-3530 2050);
WIRE 16 -1 (-6050 1550)(-7050 1550);
FORCEPROP 2 LAST SIG_NAME SMB_DEBUG_STBY_LVC3_SDA_CONN
J 0
(-6985 1560);
DISPLAY 0.680851 (-6985 1560);
PAINT ORANGE (-6985 1560);
FORCEPROP 2 LASTPROP $XR0 176 
J 0
(-7146 1550);
DISPLAY 0.638298 (-7146 1550);
PAINT MONO (-7146 1550);
WIRE 16 -1 (-6050 1600)(-7050 1600);
FORCEPROP 2 LAST SIG_NAME SMB_DEBUG_STBY_LVC3_SCL_CONN
J 0
(-6985 1610);
DISPLAY 0.680851 (-6985 1610);
PAINT ORANGE (-6985 1610);
FORCEPROP 2 LASTPROP $XR0 176 
J 0
(-7146 1600);
DISPLAY 0.638298 (-7146 1600);
PAINT MONO (-7146 1600);
WIRE 16 -1 (-650 4400)(100 4400);
FORCEPROP 2 LAST SIG_NAME DEBUG_CARD2_PRSNT
J 0
(-510 4410);
DISPLAY 0.680851 (-510 4410);
PAINT ORANGE (-510 4410);
WIRE 16 -1 (-650 4550)(200 4550);
FORCEPROP 2 LAST SIG_NAME SMB_DEBUG_STBY_LVC3_SCL_CONN
J 0
(-535 4560);
DISPLAY 0.680851 (-535 4560);
PAINT ORANGE (-535 4560);
FORCEPROP 2 LASTPROP $XR0 176 
J 0
(391 4560);
DISPLAY 0.638298 (391 4560);
PAINT MONO (391 4560);
WIRE 16 -1 (-650 4600)(200 4600);
FORCEPROP 2 LAST SIG_NAME SMB_DEBUG_STBY_LVC3_SDA_CONN
J 0
(-535 4610);
DISPLAY 0.680851 (-535 4610);
PAINT ORANGE (-535 4610);
FORCEPROP 2 LASTPROP $XR0 176 
J 0
(391 4610);
DISPLAY 0.638298 (391 4610);
PAINT MONO (391 4610);
WIRE 16 -1 (-1250 3850)(-400 3850);
FORCEPROP 2 LAST SIG_NAME SMB_DEBUG_STBY_LVC3_SDA
J 0
(-1185 3860);
DISPLAY 0.680851 (-1185 3860);
PAINT ORANGE (-1185 3860);
WIRE 16 -1 (-1250 3900)(-400 3900);
FORCEPROP 2 LAST SIG_NAME SMB_DEBUG_STBY_LVC3_SCL
J 0
(-1185 3910);
DISPLAY 0.680851 (-1185 3910);
PAINT ORANGE (-1185 3910);
WIRE 16 -1 (-5750 3000)(-6650 3000);
FORCEPROP 0 LAST SIG_NAME FM_USB_P0_EN_BOOT_BIOS_STRAP_N
J 0
(-6610 3010);
DISPLAY 0.617021 (-6610 3010);
PAINT ORANGE (-6610 3010);
WIRE 16 -1 (-3825 3325)(-3700 3325);
WIRE 16 -1 (-3700 3575)(-3700 3325);
WIRE 16 -1 (-3250 3325)(-3700 3325);
FORCEPROP 0 LAST SIG_NAME FM_OC0_USB_N
J 0
(-3610 3335);
DISPLAY 0.617021 (-3610 3335);
PAINT ORANGE (-3610 3335);
WIRE 16 -1 (-1550 2950)(-1550 2700);
FORCEPROP 2 LAST SIG_NAME SPA_MID_DBG1_TX_EN
J 0
(-1535 2785);
DISPLAY 0.617021 (-1535 2785);
PAINT ORANGE (-1535 2785);
FORCEPROP 2 LASTPROP $XRERR UNIQUE?
J 0
(-1775 2785);
DISPLAY 0.638298 (-1775 2785);
PAINT MONO (-1775 2785);
DISPLAY INVISIBLE (-1775 2785);
WIRE 16 -1 (-1400 2950)(-1550 2950);
WIRE 16 -1 (-3150 4600)(-3600 4600);
FORCEPROP 2 LAST SIG_NAME TP_USB_ESD_OUT3
J 0
(-3535 4610);
DISPLAY 0.617021 (-3535 4610);
PAINT ORANGE (-3535 4610);
FORCEPROP 2 LASTPROP $XRERR UNIQUE?
J 0
(-3070 4610);
DISPLAY 0.638298 (-3070 4610);
PAINT MONO (-3070 4610);
DISPLAY INVISIBLE (-3070 4610);
WIRE 16 -1 (-3150 4550)(-3600 4550);
FORCEPROP 2 LAST SIG_NAME TP_USB_ESD_OUT2
J 0
(-3535 4560);
DISPLAY 0.617021 (-3535 4560);
PAINT ORANGE (-3535 4560);
FORCEPROP 2 LASTPROP $XRERR UNIQUE?
J 0
(-3070 4560);
DISPLAY 0.638298 (-3070 4560);
PAINT MONO (-3070 4560);
DISPLAY INVISIBLE (-3070 4560);
WIRE 16 -1 (-5300 1900)(-5950 1900);
FORCEPROP 2 LAST SIG_NAME DEBUG_CARD2_PRSNT
J 0
(-5910 1910);
DISPLAY 0.680851 (-5910 1910);
PAINT ORANGE (-5910 1910);
FORCEPROP 2 LASTPROP $XR1 168 
J 0
(-6166 1900);
DISPLAY 0.638298 (-6166 1900);
PAINT MONO (-6166 1900);
FORCEPROP 2 LASTPROP $XR0 176 
J 0
(-6046 1900);
DISPLAY 0.638298 (-6046 1900);
PAINT MONO (-6046 1900);
WIRE 16 -1 (-3650 3250)(-3650 3425);
WIRE 16 -1 (-3825 3425)(-3650 3425);
WIRE 16 -1 (-3250 3425)(-3650 3425);
FORCEPROP 0 LAST SIG_NAME P5V_USB
J 0
(-3610 3435);
DISPLAY 0.617021 (-3610 3435);
PAINT ORANGE (-3610 3435);
WIRE 16 -1 (-5350 3750)(-5350 3850);
WIRE 16 -1 (-4950 3750)(-5350 3750);
WIRE 16 -1 (-4950 3850)(-4950 3750);
WIRE 16 -1 (-5225 3625)(-5225 3675);
WIRE 16 -1 (-5225 3675)(-4950 3675);
WIRE 16 -1 (-4950 3750)(-4950 3675);
WIRE 16 -1 (-4950 3425)(-4950 3675);
WIRE 16 -1 (-4425 3425)(-4950 3425);
FORCEPROP 2 LAST SIG_NAME P5V_TPS2061
J 0
(-4885 3460);
DISPLAY 0.808511 (-4885 3460);
PAINT ORANGE (-4885 3460);
FORCEPROP 2 LASTPROP $XRERR UNIQUE?
J 0
(-5125 3460);
DISPLAY 0.638298 (-5125 3460);
PAINT MONO (-5125 3460);
DISPLAY INVISIBLE (-5125 3460);
WIRE 16 -1 (-625 2600)(-75 2600);
FORCEPROP 2 LAST SIG_NAME SPA_MID_DBG1_TX
J 0
(-560 2610);
DISPLAY 0.617021 (-560 2610);
PAINT ORANGE (-560 2610);
WIRE 16 -1 (-600 3150)(-50 3150);
FORCEPROP 2 LAST SIG_NAME SPA_MID_DBG2_TX
J 0
(-535 3160);
DISPLAY 0.617021 (-535 3160);
PAINT ORANGE (-535 3160);
FORCEPROP 2 LASTPROP $XR0 176 
J 0
(-20 3150);
DISPLAY 0.638298 (-20 3150);
PAINT MONO (-20 3150);
WIRE 16 -1 (-4500 2000)(-3650 2000);
FORCEPROP 2 LAST SIG_NAME SMB_DEBUG_STBY_LVC3_SDA_R1
J 0
(-4385 2010);
DISPLAY 0.680851 (-4385 2010);
PAINT ORANGE (-4385 2010);
FORCEPROP 2 LASTPROP $XR0 176 
J 0
(-3530 2000);
DISPLAY 0.638298 (-3530 2000);
PAINT MONO (-3530 2000);
WIRE 16 -1 (-5850 1550)(-5000 1550);
FORCEPROP 2 LAST SIG_NAME SMB_DEBUG_STBY_LVC3_SDA_R1
J 0
(-5735 1560);
DISPLAY 0.680851 (-5735 1560);
PAINT ORANGE (-5735 1560);
FORCEPROP 2 LASTPROP $XR0 176 
J 0
(-4880 1550);
DISPLAY 0.638298 (-4880 1550);
PAINT MONO (-4880 1550);
WIRE 16 -1 (-5850 1600)(-5000 1600);
FORCEPROP 2 LAST SIG_NAME SMB_DEBUG_STBY_LVC3_SCL_R1
J 0
(-5735 1610);
DISPLAY 0.680851 (-5735 1610);
PAINT ORANGE (-5735 1610);
FORCEPROP 2 LASTPROP $XR0 176 
J 0
(-4880 1600);
DISPLAY 0.638298 (-4880 1600);
PAINT MONO (-4880 1600);
DOT 1 (-200 1650);
DOT 1 (-2150 4600);
DOT 1 (-5800 2000);
DOT 1 (-6550 4050);
DOT 1 (-5725 3950);
DOT 1 (-7200 3950);
DOT 1 (-2550 4250);
DOT 1 (-50 4250);
DOT 1 (-50 4300);
DOT 1 (-4950 3750);
DOT 1 (-1800 3150);
DOT 1 (-1450 3625);
DOT 1 (-1550 1400);
DOT 1 (-4825 5125);
DOT 1 (-5000 5125);
DOT 1 (-2950 4500);
DOT 1 (-3050 4450);
DOT 1 (-3650 3425);
DOT 1 (-3700 3325);
DOT 1 (-4950 3675);
DOT 1 (-5200 3225);
DOT 1 (-5350 3225);
DOT 1 (-6100 2050);
DOT 1 (-6100 2450);
DOT 1 (-5900 5125);
DOT 1 (-6550 3850);
DOT 1 (-5900 4925);
DOT 1 (-5000 4925);
DOT 1 (-4875 4925);
FORCENOTE
TP FAB3-DVT CHANGE L1M2 TO THE CORRECT HDL/LAYOUT SYMBOL 20161208
(-6000 4300) 0;
DISPLAY LEFT (-6000 4300);
DISPLAY 0.638298 (-6000 4300);
PAINT RED (-6000 4300);
FORCENOTE
S=1: B1
(-350 2000) 0;
DISPLAY LEFT (-350 2000);
DISPLAY 1.021277 (-350 2000);
PAINT PURPLE (-350 2000);
FORCENOTE
S=0: B0
(-350 2075) 0;
DISPLAY LEFT (-350 2075);
DISPLAY 1.021277 (-350 2075);
PAINT PURPLE (-350 2075);
FORCENOTE
NC7SB3157
(-350 2150) 0;
DISPLAY LEFT (-350 2150);
DISPLAY 1.021277 (-350 2150);
PAINT PURPLE (-350 2150);
FORCENOTE
TP FAB1 ADD AND GATE TO ISOLATE RX SIGNAL 1119
(-1250 2225) 0;
DISPLAY LEFT (-1250 2225);
DISPLAY 0.638298 (-1250 2225);
PAINT RED (-1250 2225);
FORCENOTE
TP FAB4 CHANGE AND GATE TO MUX 20170125
(-1250 2175) 0;
DISPLAY LEFT (-1250 2175);
DISPLAY 0.638298 (-1250 2175);
PAINT RED (-1250 2175);
FORCENOTE
TP FAB3 ADD R6W30 0803
(-1200 1325) 0;
DISPLAY LEFT (-1200 1325);
DISPLAY 1.021277 (-1200 1325);
PAINT RED (-1200 1325);
FORCENOTE
TP FAB3 CHANGE R6W30 0803
(-1200 1275) 0;
DISPLAY LEFT (-1200 1275);
DISPLAY 1.021277 (-1200 1275);
PAINT RED (-1200 1275);
FORCENOTE
THIS UART AND GATE IS FOR THE CASE THAT BOTH OF DEBUG INPUTS ARE PUSH-PULL.
(-3250 1125) 0;
DISPLAY LEFT (-3250 1125);
DISPLAY 1.021277 (-3250 1125);
PAINT PURPLE (-3250 1125);
FORCENOTE
TP FAB3-DVT ADD RES R6W50 20161114
(-1950 5175) 0;
DISPLAY LEFT (-1950 5175);
DISPLAY 0.638298 (-1950 5175);
PAINT RED (-1950 5175);
FORCENOTE
TP FAB4 NOPOP RES R6W50 20170124
(-1950 5125) 0;
DISPLAY LEFT (-1950 5125);
DISPLAY 0.638298 (-1950 5125);
PAINT RED (-1950 5125);
FORCENOTE
TP FAB3 ADD CIRCUIT 0803
(-2700 2250) 0;
DISPLAY LEFT (-2700 2250);
DISPLAY 1.021277 (-2700 2250);
PAINT RED (-2700 2250);
FORCENOTE
TP FAB1 ADD R1W10 AND R1W11 1221
(-4625 4000) 0;
DISPLAY LEFT (-4625 4000);
DISPLAY 1.021277 (-4625 4000);
PAINT RED (-4625 4000);
FORCENOTE
TP FAB1 CHANGE NET NAME 1117
(-3100 5400) 0;
DISPLAY LEFT (-3100 5400);
DISPLAY 0.638298 (-3100 5400);
PAINT RED (-3100 5400);
FORCENOTE
TARGET 3.3V
(-1000 3325) 0;
DISPLAY LEFT (-1000 3325);
DISPLAY 1.021277 (-1000 3325);
PAINT PURPLE (-1000 3325);
FORCENOTE
FM_USB_P0_EN_R_N
(-6500 3975) 0;
DISPLAY LEFT (-6500 3975);
DISPLAY 1.021277 (-6500 3975);
PAINT PURPLE (-6500 3975);
FORCENOTE
ENABLE
(-6500 3875) 0;
DISPLAY LEFT (-6500 3875);
DISPLAY 1.021277 (-6500 3875);
PAINT PURPLE (-6500 3875);
FORCENOTE
TP FAB3 ADD BUF 0803
(-3250 1175) 0;
DISPLAY LEFT (-3250 1175);
DISPLAY 1.021277 (-3250 1175);
PAINT RED (-3250 1175);
FORCENOTE
TP FAB3 ADD I2C CIRCUIT 0803
(-7250 1250) 0;
DISPLAY LEFT (-7250 1250);
DISPLAY 1.021277 (-7250 1250);
PAINT RED (-7250 1250);
FORCENOTE
ROOM=USB_REAR
(-7275 1050) 0;
DISPLAY LEFT (-7275 1050);
DISPLAY 0.808511 (-7275 1050);
PAINT PURPLE (-7275 1050);
FORCENOTE
TP FAB1 ADD R1W12 AND R1W13 1221
(-7150 2750) 0;
DISPLAY LEFT (-7150 2750);
DISPLAY 1.021277 (-7150 2750);
PAINT RED (-7150 2750);
FORCENOTE
TP FAB1 NOPOP R1W13 0427
(-7150 2700) 0;
DISPLAY LEFT (-7150 2700);
DISPLAY 1.021277 (-7150 2700);
PAINT RED (-7150 2700);
FORCENOTE
S0 OR S5
(-7150 3875) 0;
DISPLAY LEFT (-7150 3875);
DISPLAY 1.021277 (-7150 3875);
PAINT PURPLE (-7150 3875);
FORCENOTE
NEAR U1W3
(-4450 1350) 0;
DISPLAY LEFT (-4450 1350);
DISPLAY 1.021277 (-4450 1350);
PAINT PURPLE (-4450 1350);
FORCENOTE
TP FAB3 POP L1M2 AND NOPOP R1M5 AND R1M6 0830
(-6000 4350) 0;
DISPLAY LEFT (-6000 4350);
DISPLAY 0.638298 (-6000 4350);
PAINT RED (-6000 4350);
FORCENOTE
TP FAB3 ADD RES 0803
(-2400 3700) 0;
DISPLAY LEFT (-2400 3700);
DISPLAY 1.021277 (-2400 3700);
PAINT RED (-2400 3700);
FORCENOTE
SYSTEM STATUS
(-7150 3975) 0;
DISPLAY LEFT (-7150 3975);
DISPLAY 1.021277 (-7150 3975);
PAINT PURPLE (-7150 3975);
FORCENOTE
TP FAB1 DEL USB3.0 SIGNAL 1117
(-7150 4200) 0;
DISPLAY LEFT (-7150 4200);
DISPLAY 0.638298 (-7150 4200);
PAINT RED (-7150 4200);
FORCENOTE
$CDS_IMAGE|圖片 3.jpg|429|284
(-2475 1750) 0;
DISPLAY LEFT (-2475 1750);
QUIT
